FILE_TYPE = MACRO_DRAWING;
SET COLOR_WIRE YELLOW;
SET COLOR_PROP ORANGE;
SET COLOR_DOT WHITE;
SET COLOR_ARC YELLOW;
SET COLOR_BODY GREEN;
SET COLOR_NOTE PURPLE;
SET PROP_DISPLAY VALUE;
SET PAGE_NUMBER P86;
FORCEADD GND..1
(-2125 1825);
FORCEPROP 3 LASTPIN (-2125 1875) SIG_NAME GND\g
J 0
(-2115 1885);
DISPLAY 0.659574 (-2115 1885);
PAINT MONO (-2115 1885);
DISPLAY INVISIBLE (-2115 1885);
FORCEPROP 1 LAST VOLTAGE 0.0
J 0
(-2170 1782);
DISPLAY 0.723404 (-2170 1782);
PAINT SKYBLUE (-2170 1782);
DISPLAY INVISIBLE (-2170 1782);
FORCEPROP 2 LAST CDS_LIB mstr_symbols
J 0
(-2125 1825);
DISPLAY 0.723404 (-2125 1825);
DISPLAY INVISIBLE (-2125 1825);
FORCEPROP 1 LAST SIZE 1B
J 0
(-2050 1775);
DISPLAY 0.851064 (-2050 1775);
PAINT GREEN (-2050 1775);
DISPLAY INVISIBLE (-2050 1775);
FORCEPROP 1 LAST BODY_TYPE PLUMBING
J 0
(-2170 1782);
DISPLAY 0.340426 (-2170 1782);
PAINT GREEN (-2170 1782);
DISPLAY INVISIBLE (-2170 1782);
FORCEPROP 1 LAST HDL_POWER GND
J 0
(-2125 1975);
DISPLAY 0.851064 (-2125 1975);
PAINT GREEN (-2125 1975);
DISPLAY INVISIBLE (-2125 1975);
FORCEPROP 1 LAST PATH I150
J 0
(-2050 1825);
DISPLAY 0.872340 (-2050 1825);
PAINT GREEN (-2050 1825);
DISPLAY INVISIBLE (-2050 1825);
FORCEADD GND..1
(-325 1650);
FORCEPROP 3 LASTPIN (-325 1700) SIG_NAME GND\g
J 0
(-315 1710);
DISPLAY 0.659574 (-315 1710);
PAINT MONO (-315 1710);
DISPLAY INVISIBLE (-315 1710);
FORCEPROP 1 LAST VOLTAGE 0.0
J 0
(-370 1607);
DISPLAY 0.723404 (-370 1607);
PAINT SKYBLUE (-370 1607);
DISPLAY INVISIBLE (-370 1607);
FORCEPROP 2 LAST CDS_LIB mstr_symbols
J 0
(-325 1650);
DISPLAY 0.723404 (-325 1650);
DISPLAY INVISIBLE (-325 1650);
FORCEPROP 1 LAST SIZE 1B
J 0
(-250 1600);
DISPLAY 0.851064 (-250 1600);
PAINT GREEN (-250 1600);
DISPLAY INVISIBLE (-250 1600);
FORCEPROP 1 LAST BODY_TYPE PLUMBING
J 0
(-370 1607);
DISPLAY 0.340426 (-370 1607);
PAINT GREEN (-370 1607);
DISPLAY INVISIBLE (-370 1607);
FORCEPROP 1 LAST HDL_POWER GND
J 0
(-325 1800);
DISPLAY 0.851064 (-325 1800);
PAINT GREEN (-325 1800);
DISPLAY INVISIBLE (-325 1800);
FORCEPROP 1 LAST PATH I152
J 0
(-250 1650);
DISPLAY 0.872340 (-250 1650);
PAINT GREEN (-250 1650);
DISPLAY INVISIBLE (-250 1650);
FORCEADD OFFPAGE..5
(-8550 2075);
FORCEPROP 2 LAST $XR0 11 
J 0
(-8774 2075);
DISPLAY 0.638298 (-8774 2075);
PAINT MONO (-8774 2075);
FORCEPROP 2 LAST CDS_LIB mstr_standard
J 0
(-8550 2075);
DISPLAY 0.808511 (-8550 2075);
DISPLAY INVISIBLE (-8550 2075);
FORCEPROP 1 LAST OFFPAGE TRUE
J 0
(-8225 1950);
DISPLAY 0.872340 (-8225 1950);
PAINT GREEN (-8225 1950);
DISPLAY INVISIBLE (-8225 1950);
FORCEPROP 1 LAST COMMENT_BODY TRUE
J 0
(-8450 2000);
DISPLAY 0.872340 (-8450 2000);
PAINT GREEN (-8450 2000);
DISPLAY INVISIBLE (-8450 2000);
FORCEPROP 2 LAST PATH I167
J 0
(-8500 2150);
DISPLAY 0.808511 (-8500 2150);
DISPLAY INVISIBLE (-8500 2150);
FORCEADD OFFPAGE..5
(-8550 2125);
FORCEPROP 2 LAST $XR0 11 
J 0
(-8774 2125);
DISPLAY 0.638298 (-8774 2125);
PAINT MONO (-8774 2125);
FORCEPROP 2 LAST CDS_LIB mstr_standard
J 0
(-8550 2125);
DISPLAY 0.808511 (-8550 2125);
DISPLAY INVISIBLE (-8550 2125);
FORCEPROP 1 LAST OFFPAGE TRUE
J 0
(-8225 2000);
DISPLAY 0.872340 (-8225 2000);
PAINT GREEN (-8225 2000);
DISPLAY INVISIBLE (-8225 2000);
FORCEPROP 1 LAST COMMENT_BODY TRUE
J 0
(-8450 2050);
DISPLAY 0.872340 (-8450 2050);
PAINT GREEN (-8450 2050);
DISPLAY INVISIBLE (-8450 2050);
FORCEPROP 2 LAST PATH I168
J 0
(-8500 2200);
DISPLAY 0.808511 (-8500 2200);
DISPLAY INVISIBLE (-8500 2200);
FORCEADD OFFPAGE..6
(-8550 3725);
FORCEPROP 2 LAST $XR0 11 
J 0
(-8799 3725);
DISPLAY 0.638298 (-8799 3725);
PAINT MONO (-8799 3725);
FORCEPROP 2 LAST CDS_LIB mstr_standard
J 0
(-8550 3725);
DISPLAY 0.723404 (-8550 3725);
PAINT MONO (-8550 3725);
DISPLAY INVISIBLE (-8550 3725);
FORCEPROP 1 LAST OFFPAGE TRUE
J 0
(-8225 3600);
DISPLAY 0.872340 (-8225 3600);
PAINT GREEN (-8225 3600);
DISPLAY INVISIBLE (-8225 3600);
FORCEPROP 1 LAST COMMENT_BODY TRUE
J 0
(-8450 3650);
DISPLAY 0.872340 (-8450 3650);
PAINT GREEN (-8450 3650);
DISPLAY INVISIBLE (-8450 3650);
FORCEPROP 2 LAST PATH I174
J 0
(-8500 3800);
DISPLAY 0.808511 (-8500 3800);
DISPLAY INVISIBLE (-8500 3800);
FORCEADD OFFPAGE..1
(-8525 3225);
FORCEPROP 2 LAST $XR0 11 
J 0
(-8746 3225);
DISPLAY 0.638298 (-8746 3225);
PAINT MONO (-8746 3225);
FORCEPROP 2 LAST CDS_LIB mstr_standard
J 0
(-8525 3225);
DISPLAY 0.808511 (-8525 3225);
DISPLAY INVISIBLE (-8525 3225);
FORCEPROP 1 LAST OFFPAGE TRUE
J 0
(-8200 3100);
DISPLAY 0.872340 (-8200 3100);
PAINT GREEN (-8200 3100);
DISPLAY INVISIBLE (-8200 3100);
FORCEPROP 1 LAST COMMENT_BODY TRUE
J 0
(-8400 3125);
DISPLAY 0.872340 (-8400 3125);
PAINT GREEN (-8400 3125);
DISPLAY INVISIBLE (-8400 3125);
FORCEPROP 2 LAST PATH I176
J 0
(-8725 3450);
DISPLAY 0.808511 (-8725 3450);
DISPLAY INVISIBLE (-8725 3450);
FORCEADD VCC_CORE..1
(-8925 3575);
FORCEPROP 3 LASTPIN (-8925 3525) SIG_NAME P3V3_AUX\g
J 0
(-8915 3535);
DISPLAY 0.659574 (-8915 3535);
PAINT MONO (-8915 3535);
DISPLAY INVISIBLE (-8915 3535);
FORCEPROP 1 LAST HDL_POWER P3V3_AUX
J 1
(-8925 3625);
DISPLAY 0.489362 (-8925 3625);
PAINT GREEN (-8925 3625);
FORCEPROP 2 LAST ROOM PVCCINFAON_CPU0_CTRL
J 0
(-8925 3675);
DISPLAY 0.808511 (-8925 3675);
PAINT RED (-8925 3675);
DISPLAY INVISIBLE (-8925 3675);
FORCEPROP 0 LAST VOLTAGE 3.3
J 0
(-9200 3725);
DISPLAY 1.021277 (-9200 3725);
PAINT SKYBLUE (-9200 3725);
DISPLAY INVISIBLE (-9200 3725);
FORCEPROP 2 LAST CDS_LIB mstr_symbols
J 0
(-8925 3575);
PAINT MONO (-8925 3575);
DISPLAY INVISIBLE (-8925 3575);
FORCEPROP 1 LAST PATH I177
J 0
(-8875 3600);
DISPLAY 0.872340 (-8875 3600);
PAINT GREEN (-8875 3600);
DISPLAY INVISIBLE (-8875 3600);
FORCEADD OFFPAGE..1
(-8550 4225);
FORCEPROP 2 LAST $XR0 11 
J 0
(-8771 4225);
DISPLAY 0.638298 (-8771 4225);
PAINT MONO (-8771 4225);
FORCEPROP 2 LAST CDS_LIB mstr_standard
J 0
(-8550 4225);
DISPLAY 0.808511 (-8550 4225);
DISPLAY INVISIBLE (-8550 4225);
FORCEPROP 1 LAST OFFPAGE TRUE
J 0
(-8225 4100);
DISPLAY 0.872340 (-8225 4100);
PAINT GREEN (-8225 4100);
DISPLAY INVISIBLE (-8225 4100);
FORCEPROP 1 LAST COMMENT_BODY TRUE
J 0
(-8425 4125);
DISPLAY 0.872340 (-8425 4125);
PAINT GREEN (-8425 4125);
DISPLAY INVISIBLE (-8425 4125);
FORCEPROP 2 LAST PATH I178
J 0
(-8500 4300);
DISPLAY 0.808511 (-8500 4300);
DISPLAY INVISIBLE (-8500 4300);
FORCEADD OFFPAGE..6
(-8550 4175);
FORCEPROP 2 LAST $XR0 11 
J 0
(-8799 4175);
DISPLAY 0.638298 (-8799 4175);
PAINT MONO (-8799 4175);
FORCEPROP 2 LAST CDS_LIB mstr_standard
J 0
(-8550 4175);
DISPLAY 0.723404 (-8550 4175);
PAINT MONO (-8550 4175);
DISPLAY INVISIBLE (-8550 4175);
FORCEPROP 1 LAST OFFPAGE TRUE
J 0
(-8225 4050);
DISPLAY 0.872340 (-8225 4050);
PAINT GREEN (-8225 4050);
DISPLAY INVISIBLE (-8225 4050);
FORCEPROP 1 LAST COMMENT_BODY TRUE
J 0
(-8450 4100);
DISPLAY 0.872340 (-8450 4100);
PAINT GREEN (-8450 4100);
DISPLAY INVISIBLE (-8450 4100);
FORCEPROP 2 LAST PATH I179
J 0
(-8500 4250);
DISPLAY 0.808511 (-8500 4250);
DISPLAY INVISIBLE (-8500 4250);
FORCEADD OFFPAGE..1
(-8550 4275);
FORCEPROP 2 LAST $XR0 11 
J 0
(-8771 4275);
DISPLAY 0.638298 (-8771 4275);
PAINT MONO (-8771 4275);
FORCEPROP 2 LAST CDS_LIB mstr_standard
J 0
(-8550 4275);
DISPLAY 0.723404 (-8550 4275);
PAINT MONO (-8550 4275);
DISPLAY INVISIBLE (-8550 4275);
FORCEPROP 1 LAST OFFPAGE TRUE
J 0
(-8225 4150);
DISPLAY 0.872340 (-8225 4150);
PAINT GREEN (-8225 4150);
DISPLAY INVISIBLE (-8225 4150);
FORCEPROP 1 LAST COMMENT_BODY TRUE
J 0
(-8425 4175);
DISPLAY 0.872340 (-8425 4175);
PAINT GREEN (-8425 4175);
DISPLAY INVISIBLE (-8425 4175);
FORCEPROP 2 LAST PATH I180
J 0
(-8500 4350);
DISPLAY 0.808511 (-8500 4350);
DISPLAY INVISIBLE (-8500 4350);
FORCEADD OFFPAGE..1
(-8550 4375);
FORCEPROP 2 LAST $XR0 11 
J 0
(-8771 4375);
DISPLAY 0.638298 (-8771 4375);
PAINT MONO (-8771 4375);
FORCEPROP 2 LAST CDS_LIB mstr_standard
J 0
(-8550 4375);
DISPLAY 0.808511 (-8550 4375);
DISPLAY INVISIBLE (-8550 4375);
FORCEPROP 1 LAST OFFPAGE TRUE
J 0
(-8225 4250);
DISPLAY 0.872340 (-8225 4250);
PAINT GREEN (-8225 4250);
DISPLAY INVISIBLE (-8225 4250);
FORCEPROP 1 LAST COMMENT_BODY TRUE
J 0
(-8425 4275);
DISPLAY 0.872340 (-8425 4275);
PAINT GREEN (-8425 4275);
DISPLAY INVISIBLE (-8425 4275);
FORCEPROP 2 LAST PATH I181
J 0
(-8500 4450);
DISPLAY 0.808511 (-8500 4450);
DISPLAY INVISIBLE (-8500 4450);
FORCEADD OFFPAGE..1
(-8550 4425);
FORCEPROP 2 LAST $XR0 11 
J 0
(-8771 4425);
DISPLAY 0.638298 (-8771 4425);
PAINT MONO (-8771 4425);
FORCEPROP 2 LAST CDS_LIB mstr_standard
J 0
(-8550 4425);
DISPLAY 0.723404 (-8550 4425);
PAINT MONO (-8550 4425);
DISPLAY INVISIBLE (-8550 4425);
FORCEPROP 1 LAST OFFPAGE TRUE
J 0
(-8225 4300);
DISPLAY 0.872340 (-8225 4300);
PAINT GREEN (-8225 4300);
DISPLAY INVISIBLE (-8225 4300);
FORCEPROP 1 LAST COMMENT_BODY TRUE
J 0
(-8425 4325);
DISPLAY 0.872340 (-8425 4325);
PAINT GREEN (-8425 4325);
DISPLAY INVISIBLE (-8425 4325);
FORCEPROP 2 LAST PATH I182
J 0
(-8500 4500);
DISPLAY 0.808511 (-8500 4500);
DISPLAY INVISIBLE (-8500 4500);
FORCEADD OFFPAGE..1
(-8550 4525);
FORCEPROP 2 LAST $XR0 11 
J 0
(-8771 4525);
DISPLAY 0.638298 (-8771 4525);
PAINT MONO (-8771 4525);
FORCEPROP 2 LAST CDS_LIB mstr_standard
J 0
(-8550 4525);
DISPLAY 0.808511 (-8550 4525);
DISPLAY INVISIBLE (-8550 4525);
FORCEPROP 1 LAST OFFPAGE TRUE
J 0
(-8225 4400);
DISPLAY 0.872340 (-8225 4400);
PAINT GREEN (-8225 4400);
DISPLAY INVISIBLE (-8225 4400);
FORCEPROP 1 LAST COMMENT_BODY TRUE
J 0
(-8425 4425);
DISPLAY 0.872340 (-8425 4425);
PAINT GREEN (-8425 4425);
DISPLAY INVISIBLE (-8425 4425);
FORCEPROP 2 LAST PATH I183
J 0
(-8500 4600);
DISPLAY 0.808511 (-8500 4600);
DISPLAY INVISIBLE (-8500 4600);
FORCEADD OFFPAGE..1
(-8550 4575);
FORCEPROP 2 LAST $XR0 11 
J 0
(-8771 4575);
DISPLAY 0.638298 (-8771 4575);
PAINT MONO (-8771 4575);
FORCEPROP 2 LAST CDS_LIB mstr_standard
J 0
(-8550 4575);
DISPLAY 0.723404 (-8550 4575);
PAINT MONO (-8550 4575);
DISPLAY INVISIBLE (-8550 4575);
FORCEPROP 1 LAST OFFPAGE TRUE
J 0
(-8225 4450);
DISPLAY 0.872340 (-8225 4450);
PAINT GREEN (-8225 4450);
DISPLAY INVISIBLE (-8225 4450);
FORCEPROP 1 LAST COMMENT_BODY TRUE
J 0
(-8425 4475);
DISPLAY 0.872340 (-8425 4475);
PAINT GREEN (-8425 4475);
DISPLAY INVISIBLE (-8425 4475);
FORCEPROP 2 LAST PATH I184
J 0
(-8500 4650);
DISPLAY 0.808511 (-8500 4650);
DISPLAY INVISIBLE (-8500 4650);
FORCEADD OFFPAGE..1
(-8550 4725);
FORCEPROP 2 LAST $XR0 11 
J 0
(-8771 4725);
DISPLAY 0.638298 (-8771 4725);
PAINT MONO (-8771 4725);
FORCEPROP 2 LAST CDS_LIB mstr_standard
J 0
(-8550 4725);
DISPLAY 0.723404 (-8550 4725);
PAINT MONO (-8550 4725);
DISPLAY INVISIBLE (-8550 4725);
FORCEPROP 1 LAST OFFPAGE TRUE
J 0
(-8225 4600);
DISPLAY 0.872340 (-8225 4600);
PAINT GREEN (-8225 4600);
DISPLAY INVISIBLE (-8225 4600);
FORCEPROP 1 LAST COMMENT_BODY TRUE
J 0
(-8425 4625);
DISPLAY 0.872340 (-8425 4625);
PAINT GREEN (-8425 4625);
DISPLAY INVISIBLE (-8425 4625);
FORCEPROP 2 LAST PATH I185
J 0
(-8500 4800);
DISPLAY 0.808511 (-8500 4800);
DISPLAY INVISIBLE (-8500 4800);
FORCEADD OFFPAGE..1
(-8550 4675);
FORCEPROP 2 LAST $XR0 11 
J 0
(-8771 4675);
DISPLAY 0.638298 (-8771 4675);
PAINT MONO (-8771 4675);
FORCEPROP 2 LAST CDS_LIB mstr_standard
J 0
(-8550 4675);
DISPLAY 0.808511 (-8550 4675);
DISPLAY INVISIBLE (-8550 4675);
FORCEPROP 1 LAST OFFPAGE TRUE
J 0
(-8225 4550);
DISPLAY 0.872340 (-8225 4550);
PAINT GREEN (-8225 4550);
DISPLAY INVISIBLE (-8225 4550);
FORCEPROP 1 LAST COMMENT_BODY TRUE
J 0
(-8425 4575);
DISPLAY 0.872340 (-8425 4575);
PAINT GREEN (-8425 4575);
DISPLAY INVISIBLE (-8425 4575);
FORCEPROP 2 LAST PATH I186
J 0
(-8500 4750);
DISPLAY 0.808511 (-8500 4750);
DISPLAY INVISIBLE (-8500 4750);
FORCEADD TAP..1
R 2
(-7950 3375);
FORCEPROP 3 LASTPIN (-7900 3375) SIG_NAME M_B_CPU0_SB_CB<1>
J 0
(-7890 3385);
DISPLAY 0.659574 (-7890 3385);
PAINT MONO (-7890 3385);
DISPLAY INVISIBLE (-7890 3385);
FORCEPROP 1 LASTPIN (-7900 3375) BN 1
J 2
(-7888 3383);
DISPLAY 0.489362 (-7888 3383);
PAINT GREEN (-7888 3383);
FORCEPROP 2 LAST CDS_LIB mstr_standard
J 0
(-7950 3375);
DISPLAY 0.723404 (-7950 3375);
PAINT MONO (-7950 3375);
DISPLAY INVISIBLE (-7950 3375);
FORCEPROP 1 LAST BODY_TYPE PLUMBING
J 2
(-7950 3425);
DISPLAY 0.872340 (-7950 3425);
PAINT GREEN (-7950 3425);
DISPLAY INVISIBLE (-7950 3425);
FORCEPROP 1 LAST HDL_TAP TRUE
J 2
(-8275 3250);
DISPLAY 0.872340 (-8275 3250);
DISPLAY INVISIBLE (-8275 3250);
FORCEPROP 1 LAST PATH I187
J 2
(-7948 3375);
DISPLAY 0.872340 (-7948 3375);
PAINT GREEN (-7948 3375);
DISPLAY INVISIBLE (-7948 3375);
FORCEADD TAP..1
R 2
(-7950 3425);
FORCEPROP 3 LASTPIN (-7900 3425) SIG_NAME M_B_CPU0_SB_CB<2>
J 0
(-7890 3435);
DISPLAY 0.659574 (-7890 3435);
PAINT MONO (-7890 3435);
DISPLAY INVISIBLE (-7890 3435);
FORCEPROP 1 LASTPIN (-7900 3425) BN 2
J 2
(-7888 3433);
DISPLAY 0.489362 (-7888 3433);
PAINT GREEN (-7888 3433);
FORCEPROP 2 LAST CDS_LIB mstr_standard
J 0
(-7950 3425);
DISPLAY 0.723404 (-7950 3425);
PAINT MONO (-7950 3425);
DISPLAY INVISIBLE (-7950 3425);
FORCEPROP 1 LAST BODY_TYPE PLUMBING
J 2
(-7950 3475);
DISPLAY 0.872340 (-7950 3475);
PAINT GREEN (-7950 3475);
DISPLAY INVISIBLE (-7950 3475);
FORCEPROP 1 LAST HDL_TAP TRUE
J 2
(-8275 3300);
DISPLAY 0.872340 (-8275 3300);
DISPLAY INVISIBLE (-8275 3300);
FORCEPROP 1 LAST PATH I188
J 2
(-7948 3425);
DISPLAY 0.872340 (-7948 3425);
PAINT GREEN (-7948 3425);
DISPLAY INVISIBLE (-7948 3425);
FORCEADD TAP..1
R 2
(-7950 3325);
FORCEPROP 3 LASTPIN (-7900 3325) SIG_NAME M_B_CPU0_SB_CB<0>
J 0
(-7890 3335);
DISPLAY 0.659574 (-7890 3335);
PAINT MONO (-7890 3335);
DISPLAY INVISIBLE (-7890 3335);
FORCEPROP 1 LASTPIN (-7900 3325) BN 0
J 2
(-7888 3333);
DISPLAY 0.489362 (-7888 3333);
PAINT GREEN (-7888 3333);
FORCEPROP 2 LAST CDS_LIB mstr_standard
J 0
(-7950 3325);
DISPLAY 0.723404 (-7950 3325);
PAINT MONO (-7950 3325);
DISPLAY INVISIBLE (-7950 3325);
FORCEPROP 1 LAST BODY_TYPE PLUMBING
J 2
(-7950 3375);
DISPLAY 0.872340 (-7950 3375);
PAINT GREEN (-7950 3375);
DISPLAY INVISIBLE (-7950 3375);
FORCEPROP 1 LAST HDL_TAP TRUE
J 2
(-8275 3200);
DISPLAY 0.872340 (-8275 3200);
DISPLAY INVISIBLE (-8275 3200);
FORCEPROP 1 LAST PATH I189
J 2
(-7948 3325);
DISPLAY 0.872340 (-7948 3325);
PAINT GREEN (-7948 3325);
DISPLAY INVISIBLE (-7948 3325);
FORCEADD TAP..1
R 2
(-7950 3475);
FORCEPROP 3 LASTPIN (-7900 3475) SIG_NAME M_B_CPU0_SB_CB<3>
J 0
(-7890 3485);
DISPLAY 0.659574 (-7890 3485);
PAINT MONO (-7890 3485);
DISPLAY INVISIBLE (-7890 3485);
FORCEPROP 1 LASTPIN (-7900 3475) BN 3
J 2
(-7888 3483);
DISPLAY 0.489362 (-7888 3483);
PAINT GREEN (-7888 3483);
FORCEPROP 2 LAST CDS_LIB mstr_standard
J 0
(-7950 3475);
DISPLAY 0.723404 (-7950 3475);
PAINT MONO (-7950 3475);
DISPLAY INVISIBLE (-7950 3475);
FORCEPROP 1 LAST BODY_TYPE PLUMBING
J 2
(-7950 3525);
DISPLAY 0.872340 (-7950 3525);
PAINT GREEN (-7950 3525);
DISPLAY INVISIBLE (-7950 3525);
FORCEPROP 1 LAST HDL_TAP TRUE
J 2
(-8275 3350);
DISPLAY 0.872340 (-8275 3350);
DISPLAY INVISIBLE (-8275 3350);
FORCEPROP 1 LAST PATH I190
J 2
(-7948 3475);
DISPLAY 0.872340 (-7948 3475);
PAINT GREEN (-7948 3475);
DISPLAY INVISIBLE (-7948 3475);
FORCEADD TAP..1
R 2
(-7950 3525);
FORCEPROP 3 LASTPIN (-7900 3525) SIG_NAME M_B_CPU0_SB_CB<4>
J 0
(-7890 3535);
DISPLAY 0.659574 (-7890 3535);
PAINT MONO (-7890 3535);
DISPLAY INVISIBLE (-7890 3535);
FORCEPROP 1 LASTPIN (-7900 3525) BN 4
J 2
(-7888 3533);
DISPLAY 0.489362 (-7888 3533);
PAINT GREEN (-7888 3533);
FORCEPROP 2 LAST CDS_LIB mstr_standard
J 0
(-7950 3525);
DISPLAY 0.723404 (-7950 3525);
PAINT MONO (-7950 3525);
DISPLAY INVISIBLE (-7950 3525);
FORCEPROP 1 LAST BODY_TYPE PLUMBING
J 2
(-7950 3575);
DISPLAY 0.872340 (-7950 3575);
PAINT GREEN (-7950 3575);
DISPLAY INVISIBLE (-7950 3575);
FORCEPROP 1 LAST HDL_TAP TRUE
J 2
(-8275 3400);
DISPLAY 0.872340 (-8275 3400);
DISPLAY INVISIBLE (-8275 3400);
FORCEPROP 1 LAST PATH I191
J 2
(-7948 3525);
DISPLAY 0.872340 (-7948 3525);
PAINT GREEN (-7948 3525);
DISPLAY INVISIBLE (-7948 3525);
FORCEADD TAP..1
R 2
(-7950 3575);
FORCEPROP 3 LASTPIN (-7900 3575) SIG_NAME M_B_CPU0_SB_CB<5>
J 0
(-7890 3585);
DISPLAY 0.659574 (-7890 3585);
PAINT MONO (-7890 3585);
DISPLAY INVISIBLE (-7890 3585);
FORCEPROP 1 LASTPIN (-7900 3575) BN 5
J 2
(-7888 3583);
DISPLAY 0.489362 (-7888 3583);
PAINT GREEN (-7888 3583);
FORCEPROP 2 LAST CDS_LIB mstr_standard
J 0
(-7950 3575);
DISPLAY 0.723404 (-7950 3575);
PAINT MONO (-7950 3575);
DISPLAY INVISIBLE (-7950 3575);
FORCEPROP 1 LAST BODY_TYPE PLUMBING
J 2
(-7950 3625);
DISPLAY 0.872340 (-7950 3625);
PAINT GREEN (-7950 3625);
DISPLAY INVISIBLE (-7950 3625);
FORCEPROP 1 LAST HDL_TAP TRUE
J 2
(-8275 3450);
DISPLAY 0.872340 (-8275 3450);
DISPLAY INVISIBLE (-8275 3450);
FORCEPROP 1 LAST PATH I192
J 2
(-7948 3575);
DISPLAY 0.872340 (-7948 3575);
PAINT GREEN (-7948 3575);
DISPLAY INVISIBLE (-7948 3575);
FORCEADD TAP..1
R 2
(-7950 3675);
FORCEPROP 3 LASTPIN (-7900 3675) SIG_NAME M_B_CPU0_SB_CB<7>
J 0
(-7890 3685);
DISPLAY 0.659574 (-7890 3685);
PAINT MONO (-7890 3685);
DISPLAY INVISIBLE (-7890 3685);
FORCEPROP 1 LASTPIN (-7900 3675) BN 7
J 2
(-7888 3683);
DISPLAY 0.489362 (-7888 3683);
PAINT GREEN (-7888 3683);
FORCEPROP 2 LAST CDS_LIB mstr_standard
J 0
(-7950 3675);
DISPLAY 0.723404 (-7950 3675);
PAINT MONO (-7950 3675);
DISPLAY INVISIBLE (-7950 3675);
FORCEPROP 1 LAST BODY_TYPE PLUMBING
J 2
(-7950 3725);
DISPLAY 0.872340 (-7950 3725);
PAINT GREEN (-7950 3725);
DISPLAY INVISIBLE (-7950 3725);
FORCEPROP 1 LAST HDL_TAP TRUE
J 2
(-8275 3550);
DISPLAY 0.872340 (-8275 3550);
DISPLAY INVISIBLE (-8275 3550);
FORCEPROP 1 LAST PATH I193
J 2
(-7948 3675);
DISPLAY 0.872340 (-7948 3675);
PAINT GREEN (-7948 3675);
DISPLAY INVISIBLE (-7948 3675);
FORCEADD TAP..1
R 2
(-7950 3625);
FORCEPROP 3 LASTPIN (-7900 3625) SIG_NAME M_B_CPU0_SB_CB<6>
J 0
(-7890 3635);
DISPLAY 0.659574 (-7890 3635);
PAINT MONO (-7890 3635);
DISPLAY INVISIBLE (-7890 3635);
FORCEPROP 1 LASTPIN (-7900 3625) BN 6
J 2
(-7888 3633);
DISPLAY 0.489362 (-7888 3633);
PAINT GREEN (-7888 3633);
FORCEPROP 2 LAST CDS_LIB mstr_standard
J 0
(-7950 3625);
DISPLAY 0.723404 (-7950 3625);
PAINT MONO (-7950 3625);
DISPLAY INVISIBLE (-7950 3625);
FORCEPROP 1 LAST BODY_TYPE PLUMBING
J 2
(-7950 3675);
DISPLAY 0.872340 (-7950 3675);
PAINT GREEN (-7950 3675);
DISPLAY INVISIBLE (-7950 3675);
FORCEPROP 1 LAST HDL_TAP TRUE
J 2
(-8275 3500);
DISPLAY 0.872340 (-8275 3500);
DISPLAY INVISIBLE (-8275 3500);
FORCEPROP 1 LAST PATH I194
J 2
(-7948 3625);
DISPLAY 0.872340 (-7948 3625);
PAINT GREEN (-7948 3625);
DISPLAY INVISIBLE (-7948 3625);
FORCEADD TAP..1
R 2
(-7950 3875);
FORCEPROP 3 LASTPIN (-7900 3875) SIG_NAME M_B_CPU0_SA_CB<2>
J 0
(-7890 3885);
DISPLAY 0.659574 (-7890 3885);
PAINT MONO (-7890 3885);
DISPLAY INVISIBLE (-7890 3885);
FORCEPROP 1 LASTPIN (-7900 3875) BN 2
J 2
(-7888 3883);
DISPLAY 0.489362 (-7888 3883);
PAINT GREEN (-7888 3883);
FORCEPROP 2 LAST CDS_LIB mstr_standard
J 0
(-7950 3875);
DISPLAY 0.723404 (-7950 3875);
PAINT MONO (-7950 3875);
DISPLAY INVISIBLE (-7950 3875);
FORCEPROP 1 LAST BODY_TYPE PLUMBING
J 2
(-7950 3925);
DISPLAY 0.872340 (-7950 3925);
PAINT GREEN (-7950 3925);
DISPLAY INVISIBLE (-7950 3925);
FORCEPROP 1 LAST HDL_TAP TRUE
J 2
(-8275 3750);
DISPLAY 0.872340 (-8275 3750);
DISPLAY INVISIBLE (-8275 3750);
FORCEPROP 1 LAST PATH I195
J 2
(-7948 3875);
DISPLAY 0.872340 (-7948 3875);
PAINT GREEN (-7948 3875);
DISPLAY INVISIBLE (-7948 3875);
FORCEADD TAP..1
R 2
(-7950 3825);
FORCEPROP 3 LASTPIN (-7900 3825) SIG_NAME M_B_CPU0_SA_CB<1>
J 0
(-7890 3835);
DISPLAY 0.659574 (-7890 3835);
PAINT MONO (-7890 3835);
DISPLAY INVISIBLE (-7890 3835);
FORCEPROP 1 LASTPIN (-7900 3825) BN 1
J 2
(-7888 3833);
DISPLAY 0.489362 (-7888 3833);
PAINT GREEN (-7888 3833);
FORCEPROP 2 LAST CDS_LIB mstr_standard
J 0
(-7950 3825);
DISPLAY 0.723404 (-7950 3825);
PAINT MONO (-7950 3825);
DISPLAY INVISIBLE (-7950 3825);
FORCEPROP 1 LAST BODY_TYPE PLUMBING
J 2
(-7950 3875);
DISPLAY 0.872340 (-7950 3875);
PAINT GREEN (-7950 3875);
DISPLAY INVISIBLE (-7950 3875);
FORCEPROP 1 LAST HDL_TAP TRUE
J 2
(-8275 3700);
DISPLAY 0.872340 (-8275 3700);
DISPLAY INVISIBLE (-8275 3700);
FORCEPROP 1 LAST PATH I196
J 2
(-7948 3825);
DISPLAY 0.872340 (-7948 3825);
PAINT GREEN (-7948 3825);
DISPLAY INVISIBLE (-7948 3825);
FORCEADD TAP..1
R 2
(-7950 3775);
FORCEPROP 3 LASTPIN (-7900 3775) SIG_NAME M_B_CPU0_SA_CB<0>
J 0
(-7890 3785);
DISPLAY 0.659574 (-7890 3785);
PAINT MONO (-7890 3785);
DISPLAY INVISIBLE (-7890 3785);
FORCEPROP 1 LASTPIN (-7900 3775) BN 0
J 2
(-7888 3783);
DISPLAY 0.489362 (-7888 3783);
PAINT GREEN (-7888 3783);
FORCEPROP 2 LAST CDS_LIB mstr_standard
J 0
(-7950 3775);
DISPLAY 0.723404 (-7950 3775);
PAINT MONO (-7950 3775);
DISPLAY INVISIBLE (-7950 3775);
FORCEPROP 1 LAST BODY_TYPE PLUMBING
J 2
(-7950 3825);
DISPLAY 0.872340 (-7950 3825);
PAINT GREEN (-7950 3825);
DISPLAY INVISIBLE (-7950 3825);
FORCEPROP 1 LAST HDL_TAP TRUE
J 2
(-8275 3650);
DISPLAY 0.872340 (-8275 3650);
DISPLAY INVISIBLE (-8275 3650);
FORCEPROP 1 LAST PATH I197
J 2
(-7948 3775);
DISPLAY 0.872340 (-7948 3775);
PAINT GREEN (-7948 3775);
DISPLAY INVISIBLE (-7948 3775);
FORCEADD TAP..1
R 2
(-7950 3925);
FORCEPROP 3 LASTPIN (-7900 3925) SIG_NAME M_B_CPU0_SA_CB<3>
J 0
(-7890 3935);
DISPLAY 0.659574 (-7890 3935);
PAINT MONO (-7890 3935);
DISPLAY INVISIBLE (-7890 3935);
FORCEPROP 1 LASTPIN (-7900 3925) BN 3
J 2
(-7888 3933);
DISPLAY 0.489362 (-7888 3933);
PAINT GREEN (-7888 3933);
FORCEPROP 2 LAST CDS_LIB mstr_standard
J 0
(-7950 3925);
DISPLAY 0.723404 (-7950 3925);
PAINT MONO (-7950 3925);
DISPLAY INVISIBLE (-7950 3925);
FORCEPROP 1 LAST BODY_TYPE PLUMBING
J 2
(-7950 3975);
DISPLAY 0.872340 (-7950 3975);
PAINT GREEN (-7950 3975);
DISPLAY INVISIBLE (-7950 3975);
FORCEPROP 1 LAST HDL_TAP TRUE
J 2
(-8275 3800);
DISPLAY 0.872340 (-8275 3800);
DISPLAY INVISIBLE (-8275 3800);
FORCEPROP 1 LAST PATH I198
J 2
(-7948 3925);
DISPLAY 0.872340 (-7948 3925);
PAINT GREEN (-7948 3925);
DISPLAY INVISIBLE (-7948 3925);
FORCEADD TAP..1
R 2
(-7950 3975);
FORCEPROP 3 LASTPIN (-7900 3975) SIG_NAME M_B_CPU0_SA_CB<4>
J 0
(-7890 3985);
DISPLAY 0.659574 (-7890 3985);
PAINT MONO (-7890 3985);
DISPLAY INVISIBLE (-7890 3985);
FORCEPROP 1 LASTPIN (-7900 3975) BN 4
J 2
(-7888 3983);
DISPLAY 0.489362 (-7888 3983);
PAINT GREEN (-7888 3983);
FORCEPROP 2 LAST CDS_LIB mstr_standard
J 0
(-7950 3975);
DISPLAY 0.723404 (-7950 3975);
PAINT MONO (-7950 3975);
DISPLAY INVISIBLE (-7950 3975);
FORCEPROP 1 LAST BODY_TYPE PLUMBING
J 2
(-7950 4025);
DISPLAY 0.872340 (-7950 4025);
PAINT GREEN (-7950 4025);
DISPLAY INVISIBLE (-7950 4025);
FORCEPROP 1 LAST HDL_TAP TRUE
J 2
(-8275 3850);
DISPLAY 0.872340 (-8275 3850);
DISPLAY INVISIBLE (-8275 3850);
FORCEPROP 1 LAST PATH I199
J 2
(-7948 3975);
DISPLAY 0.872340 (-7948 3975);
PAINT GREEN (-7948 3975);
DISPLAY INVISIBLE (-7948 3975);
FORCEADD TAP..1
R 2
(-7950 4025);
FORCEPROP 3 LASTPIN (-7900 4025) SIG_NAME M_B_CPU0_SA_CB<5>
J 0
(-7890 4035);
DISPLAY 0.659574 (-7890 4035);
PAINT MONO (-7890 4035);
DISPLAY INVISIBLE (-7890 4035);
FORCEPROP 1 LASTPIN (-7900 4025) BN 5
J 2
(-7888 4033);
DISPLAY 0.489362 (-7888 4033);
PAINT GREEN (-7888 4033);
FORCEPROP 2 LAST CDS_LIB mstr_standard
J 0
(-7950 4025);
DISPLAY 0.723404 (-7950 4025);
PAINT MONO (-7950 4025);
DISPLAY INVISIBLE (-7950 4025);
FORCEPROP 1 LAST BODY_TYPE PLUMBING
J 2
(-7950 4075);
DISPLAY 0.872340 (-7950 4075);
PAINT GREEN (-7950 4075);
DISPLAY INVISIBLE (-7950 4075);
FORCEPROP 1 LAST HDL_TAP TRUE
J 2
(-8275 3900);
DISPLAY 0.872340 (-8275 3900);
DISPLAY INVISIBLE (-8275 3900);
FORCEPROP 1 LAST PATH I200
J 2
(-7948 4025);
DISPLAY 0.872340 (-7948 4025);
PAINT GREEN (-7948 4025);
DISPLAY INVISIBLE (-7948 4025);
FORCEADD TAP..1
R 2
(-7950 4075);
FORCEPROP 3 LASTPIN (-7900 4075) SIG_NAME M_B_CPU0_SA_CB<6>
J 0
(-7890 4085);
DISPLAY 0.659574 (-7890 4085);
PAINT MONO (-7890 4085);
DISPLAY INVISIBLE (-7890 4085);
FORCEPROP 1 LASTPIN (-7900 4075) BN 6
J 2
(-7888 4083);
DISPLAY 0.489362 (-7888 4083);
PAINT GREEN (-7888 4083);
FORCEPROP 2 LAST CDS_LIB mstr_standard
J 0
(-7950 4075);
DISPLAY 0.723404 (-7950 4075);
PAINT MONO (-7950 4075);
DISPLAY INVISIBLE (-7950 4075);
FORCEPROP 1 LAST BODY_TYPE PLUMBING
J 2
(-7950 4125);
DISPLAY 0.872340 (-7950 4125);
PAINT GREEN (-7950 4125);
DISPLAY INVISIBLE (-7950 4125);
FORCEPROP 1 LAST HDL_TAP TRUE
J 2
(-8275 3950);
DISPLAY 0.872340 (-8275 3950);
DISPLAY INVISIBLE (-8275 3950);
FORCEPROP 1 LAST PATH I201
J 2
(-7948 4075);
DISPLAY 0.872340 (-7948 4075);
PAINT GREEN (-7948 4075);
DISPLAY INVISIBLE (-7948 4075);
FORCEADD TAP..1
R 2
(-7950 4125);
FORCEPROP 3 LASTPIN (-7900 4125) SIG_NAME M_B_CPU0_SA_CB<7>
J 0
(-7890 4135);
DISPLAY 0.659574 (-7890 4135);
PAINT MONO (-7890 4135);
DISPLAY INVISIBLE (-7890 4135);
FORCEPROP 1 LASTPIN (-7900 4125) BN 7
J 2
(-7888 4133);
DISPLAY 0.489362 (-7888 4133);
PAINT GREEN (-7888 4133);
FORCEPROP 2 LAST CDS_LIB mstr_standard
J 0
(-7950 4125);
DISPLAY 0.723404 (-7950 4125);
PAINT MONO (-7950 4125);
DISPLAY INVISIBLE (-7950 4125);
FORCEPROP 1 LAST BODY_TYPE PLUMBING
J 2
(-7950 4175);
DISPLAY 0.872340 (-7950 4175);
PAINT GREEN (-7950 4175);
DISPLAY INVISIBLE (-7950 4175);
FORCEPROP 1 LAST HDL_TAP TRUE
J 2
(-8275 4000);
DISPLAY 0.872340 (-8275 4000);
DISPLAY INVISIBLE (-8275 4000);
FORCEPROP 1 LAST PATH I202
J 2
(-7948 4125);
DISPLAY 0.872340 (-7948 4125);
PAINT GREEN (-7948 4125);
DISPLAY INVISIBLE (-7948 4125);
FORCEADD TAP..1
R 2
(-7950 4975);
FORCEPROP 3 LASTPIN (-7900 4975) SIG_NAME M_B_CPU0_SB_CA<3>
J 0
(-7890 4985);
DISPLAY 0.659574 (-7890 4985);
PAINT MONO (-7890 4985);
DISPLAY INVISIBLE (-7890 4985);
FORCEPROP 1 LASTPIN (-7900 4975) BN 3
J 2
(-7888 4983);
DISPLAY 0.489362 (-7888 4983);
PAINT GREEN (-7888 4983);
FORCEPROP 2 LAST CDS_LIB mstr_standard
J 0
(-7950 4975);
DISPLAY 0.723404 (-7950 4975);
PAINT MONO (-7950 4975);
DISPLAY INVISIBLE (-7950 4975);
FORCEPROP 1 LAST BODY_TYPE PLUMBING
J 2
(-7950 5025);
DISPLAY 0.872340 (-7950 5025);
PAINT GREEN (-7950 5025);
DISPLAY INVISIBLE (-7950 5025);
FORCEPROP 1 LAST HDL_TAP TRUE
J 2
(-8275 4850);
DISPLAY 0.872340 (-8275 4850);
DISPLAY INVISIBLE (-8275 4850);
FORCEPROP 1 LAST PATH I203
J 2
(-7948 4975);
DISPLAY 0.872340 (-7948 4975);
PAINT GREEN (-7948 4975);
DISPLAY INVISIBLE (-7948 4975);
FORCEADD TAP..1
R 2
(-7950 4875);
FORCEPROP 3 LASTPIN (-7900 4875) SIG_NAME M_B_CPU0_SB_CA<1>
J 0
(-7890 4885);
DISPLAY 0.659574 (-7890 4885);
PAINT MONO (-7890 4885);
DISPLAY INVISIBLE (-7890 4885);
FORCEPROP 1 LASTPIN (-7900 4875) BN 1
J 2
(-7888 4883);
DISPLAY 0.489362 (-7888 4883);
PAINT GREEN (-7888 4883);
FORCEPROP 2 LAST CDS_LIB mstr_standard
J 0
(-7950 4875);
DISPLAY 0.723404 (-7950 4875);
PAINT MONO (-7950 4875);
DISPLAY INVISIBLE (-7950 4875);
FORCEPROP 1 LAST BODY_TYPE PLUMBING
J 2
(-7950 4925);
DISPLAY 0.872340 (-7950 4925);
PAINT GREEN (-7950 4925);
DISPLAY INVISIBLE (-7950 4925);
FORCEPROP 1 LAST HDL_TAP TRUE
J 2
(-8275 4750);
DISPLAY 0.872340 (-8275 4750);
DISPLAY INVISIBLE (-8275 4750);
FORCEPROP 1 LAST PATH I204
J 2
(-7948 4875);
DISPLAY 0.872340 (-7948 4875);
PAINT GREEN (-7948 4875);
DISPLAY INVISIBLE (-7948 4875);
FORCEADD TAP..1
R 2
(-7950 4825);
FORCEPROP 3 LASTPIN (-7900 4825) SIG_NAME M_B_CPU0_SB_CA<0>
J 0
(-7890 4835);
DISPLAY 0.659574 (-7890 4835);
PAINT MONO (-7890 4835);
DISPLAY INVISIBLE (-7890 4835);
FORCEPROP 1 LASTPIN (-7900 4825) BN 0
J 2
(-7888 4833);
DISPLAY 0.489362 (-7888 4833);
PAINT GREEN (-7888 4833);
FORCEPROP 2 LAST CDS_LIB mstr_standard
J 0
(-7950 4825);
DISPLAY 0.723404 (-7950 4825);
PAINT MONO (-7950 4825);
DISPLAY INVISIBLE (-7950 4825);
FORCEPROP 1 LAST BODY_TYPE PLUMBING
J 2
(-7950 4875);
DISPLAY 0.872340 (-7950 4875);
PAINT GREEN (-7950 4875);
DISPLAY INVISIBLE (-7950 4875);
FORCEPROP 1 LAST HDL_TAP TRUE
J 2
(-8275 4700);
DISPLAY 0.872340 (-8275 4700);
DISPLAY INVISIBLE (-8275 4700);
FORCEPROP 1 LAST PATH I205
J 2
(-7948 4825);
DISPLAY 0.872340 (-7948 4825);
PAINT GREEN (-7948 4825);
DISPLAY INVISIBLE (-7948 4825);
FORCEADD TAP..1
R 2
(-7950 4925);
FORCEPROP 3 LASTPIN (-7900 4925) SIG_NAME M_B_CPU0_SB_CA<2>
J 0
(-7890 4935);
DISPLAY 0.659574 (-7890 4935);
PAINT MONO (-7890 4935);
DISPLAY INVISIBLE (-7890 4935);
FORCEPROP 1 LASTPIN (-7900 4925) BN 2
J 2
(-7888 4933);
DISPLAY 0.489362 (-7888 4933);
PAINT GREEN (-7888 4933);
FORCEPROP 2 LAST CDS_LIB mstr_standard
J 0
(-7950 4925);
DISPLAY 0.723404 (-7950 4925);
PAINT MONO (-7950 4925);
DISPLAY INVISIBLE (-7950 4925);
FORCEPROP 1 LAST BODY_TYPE PLUMBING
J 2
(-7950 4975);
DISPLAY 0.872340 (-7950 4975);
PAINT GREEN (-7950 4975);
DISPLAY INVISIBLE (-7950 4975);
FORCEPROP 1 LAST HDL_TAP TRUE
J 2
(-8275 4800);
DISPLAY 0.872340 (-8275 4800);
DISPLAY INVISIBLE (-8275 4800);
FORCEPROP 1 LAST PATH I206
J 2
(-7948 4925);
DISPLAY 0.872340 (-7948 4925);
PAINT GREEN (-7948 4925);
DISPLAY INVISIBLE (-7948 4925);
FORCEADD TAP..1
(-6250 2375);
FORCEPROP 3 LASTPIN (-6300 2375) SIG_NAME M_B_CPU0_SB_DQ<1>
J 0
(-6290 2385);
DISPLAY 0.659574 (-6290 2385);
PAINT MONO (-6290 2385);
DISPLAY INVISIBLE (-6290 2385);
FORCEPROP 1 LASTPIN (-6300 2375) BN 1
J 0
(-6312 2383);
DISPLAY 0.489362 (-6312 2383);
PAINT GREEN (-6312 2383);
FORCEPROP 2 LAST CDS_LIB mstr_standard
J 0
(-6250 2375);
DISPLAY 0.723404 (-6250 2375);
PAINT MONO (-6250 2375);
DISPLAY INVISIBLE (-6250 2375);
FORCEPROP 1 LAST BODY_TYPE PLUMBING
J 0
(-6250 2425);
DISPLAY 0.872340 (-6250 2425);
PAINT GREEN (-6250 2425);
DISPLAY INVISIBLE (-6250 2425);
FORCEPROP 1 LAST HDL_TAP TRUE
J 0
(-5925 2250);
DISPLAY 0.872340 (-5925 2250);
DISPLAY INVISIBLE (-5925 2250);
FORCEPROP 1 LAST PATH I207
J 0
(-6252 2375);
DISPLAY 0.872340 (-6252 2375);
PAINT GREEN (-6252 2375);
DISPLAY INVISIBLE (-6252 2375);
FORCEADD TAP..1
(-6250 2325);
FORCEPROP 3 LASTPIN (-6300 2325) SIG_NAME M_B_CPU0_SB_DQ<0>
J 0
(-6290 2335);
DISPLAY 0.659574 (-6290 2335);
PAINT MONO (-6290 2335);
DISPLAY INVISIBLE (-6290 2335);
FORCEPROP 1 LASTPIN (-6300 2325) BN 0
J 0
(-6312 2333);
DISPLAY 0.489362 (-6312 2333);
PAINT GREEN (-6312 2333);
FORCEPROP 2 LAST CDS_LIB mstr_standard
J 0
(-6250 2325);
DISPLAY 0.723404 (-6250 2325);
PAINT MONO (-6250 2325);
DISPLAY INVISIBLE (-6250 2325);
FORCEPROP 1 LAST BODY_TYPE PLUMBING
J 0
(-6250 2375);
DISPLAY 0.872340 (-6250 2375);
PAINT GREEN (-6250 2375);
DISPLAY INVISIBLE (-6250 2375);
FORCEPROP 1 LAST HDL_TAP TRUE
J 0
(-5925 2200);
DISPLAY 0.872340 (-5925 2200);
DISPLAY INVISIBLE (-5925 2200);
FORCEPROP 1 LAST PATH I208
J 0
(-6252 2325);
DISPLAY 0.872340 (-6252 2325);
PAINT GREEN (-6252 2325);
DISPLAY INVISIBLE (-6252 2325);
FORCEADD TAP..1
(-6250 2425);
FORCEPROP 3 LASTPIN (-6300 2425) SIG_NAME M_B_CPU0_SB_DQ<2>
J 0
(-6290 2435);
DISPLAY 0.659574 (-6290 2435);
PAINT MONO (-6290 2435);
DISPLAY INVISIBLE (-6290 2435);
FORCEPROP 1 LASTPIN (-6300 2425) BN 2
J 0
(-6312 2433);
DISPLAY 0.489362 (-6312 2433);
PAINT GREEN (-6312 2433);
FORCEPROP 2 LAST CDS_LIB mstr_standard
J 0
(-6250 2425);
DISPLAY 0.723404 (-6250 2425);
PAINT MONO (-6250 2425);
DISPLAY INVISIBLE (-6250 2425);
FORCEPROP 1 LAST BODY_TYPE PLUMBING
J 0
(-6250 2475);
DISPLAY 0.872340 (-6250 2475);
PAINT GREEN (-6250 2475);
DISPLAY INVISIBLE (-6250 2475);
FORCEPROP 1 LAST HDL_TAP TRUE
J 0
(-5925 2300);
DISPLAY 0.872340 (-5925 2300);
DISPLAY INVISIBLE (-5925 2300);
FORCEPROP 1 LAST PATH I209
J 0
(-6252 2425);
DISPLAY 0.872340 (-6252 2425);
PAINT GREEN (-6252 2425);
DISPLAY INVISIBLE (-6252 2425);
FORCEADD TAP..1
(-6250 2475);
FORCEPROP 3 LASTPIN (-6300 2475) SIG_NAME M_B_CPU0_SB_DQ<3>
J 0
(-6290 2485);
DISPLAY 0.659574 (-6290 2485);
PAINT MONO (-6290 2485);
DISPLAY INVISIBLE (-6290 2485);
FORCEPROP 1 LASTPIN (-6300 2475) BN 3
J 0
(-6312 2483);
DISPLAY 0.489362 (-6312 2483);
PAINT GREEN (-6312 2483);
FORCEPROP 2 LAST CDS_LIB mstr_standard
J 0
(-6250 2475);
DISPLAY 0.723404 (-6250 2475);
PAINT MONO (-6250 2475);
DISPLAY INVISIBLE (-6250 2475);
FORCEPROP 1 LAST BODY_TYPE PLUMBING
J 0
(-6250 2525);
DISPLAY 0.872340 (-6250 2525);
PAINT GREEN (-6250 2525);
DISPLAY INVISIBLE (-6250 2525);
FORCEPROP 1 LAST HDL_TAP TRUE
J 0
(-5925 2350);
DISPLAY 0.872340 (-5925 2350);
DISPLAY INVISIBLE (-5925 2350);
FORCEPROP 1 LAST PATH I210
J 0
(-6252 2475);
DISPLAY 0.872340 (-6252 2475);
PAINT GREEN (-6252 2475);
DISPLAY INVISIBLE (-6252 2475);
FORCEADD TAP..1
(-6250 2525);
FORCEPROP 3 LASTPIN (-6300 2525) SIG_NAME M_B_CPU0_SB_DQ<4>
J 0
(-6290 2535);
DISPLAY 0.659574 (-6290 2535);
PAINT MONO (-6290 2535);
DISPLAY INVISIBLE (-6290 2535);
FORCEPROP 1 LASTPIN (-6300 2525) BN 4
J 0
(-6312 2533);
DISPLAY 0.489362 (-6312 2533);
PAINT GREEN (-6312 2533);
FORCEPROP 2 LAST CDS_LIB mstr_standard
J 0
(-6250 2525);
DISPLAY 0.723404 (-6250 2525);
PAINT MONO (-6250 2525);
DISPLAY INVISIBLE (-6250 2525);
FORCEPROP 1 LAST BODY_TYPE PLUMBING
J 0
(-6250 2575);
DISPLAY 0.872340 (-6250 2575);
PAINT GREEN (-6250 2575);
DISPLAY INVISIBLE (-6250 2575);
FORCEPROP 1 LAST HDL_TAP TRUE
J 0
(-5925 2400);
DISPLAY 0.872340 (-5925 2400);
DISPLAY INVISIBLE (-5925 2400);
FORCEPROP 1 LAST PATH I211
J 0
(-6252 2525);
DISPLAY 0.872340 (-6252 2525);
PAINT GREEN (-6252 2525);
DISPLAY INVISIBLE (-6252 2525);
FORCEADD TAP..1
(-6250 2575);
FORCEPROP 3 LASTPIN (-6300 2575) SIG_NAME M_B_CPU0_SB_DQ<5>
J 0
(-6290 2585);
DISPLAY 0.659574 (-6290 2585);
PAINT MONO (-6290 2585);
DISPLAY INVISIBLE (-6290 2585);
FORCEPROP 1 LASTPIN (-6300 2575) BN 5
J 0
(-6312 2583);
DISPLAY 0.489362 (-6312 2583);
PAINT GREEN (-6312 2583);
FORCEPROP 2 LAST CDS_LIB mstr_standard
J 0
(-6250 2575);
DISPLAY 0.723404 (-6250 2575);
PAINT MONO (-6250 2575);
DISPLAY INVISIBLE (-6250 2575);
FORCEPROP 1 LAST BODY_TYPE PLUMBING
J 0
(-6250 2625);
DISPLAY 0.872340 (-6250 2625);
PAINT GREEN (-6250 2625);
DISPLAY INVISIBLE (-6250 2625);
FORCEPROP 1 LAST HDL_TAP TRUE
J 0
(-5925 2450);
DISPLAY 0.872340 (-5925 2450);
DISPLAY INVISIBLE (-5925 2450);
FORCEPROP 1 LAST PATH I212
J 0
(-6252 2575);
DISPLAY 0.872340 (-6252 2575);
PAINT GREEN (-6252 2575);
DISPLAY INVISIBLE (-6252 2575);
FORCEADD TAP..1
(-6250 2675);
FORCEPROP 3 LASTPIN (-6300 2675) SIG_NAME M_B_CPU0_SB_DQ<7>
J 0
(-6290 2685);
DISPLAY 0.659574 (-6290 2685);
PAINT MONO (-6290 2685);
DISPLAY INVISIBLE (-6290 2685);
FORCEPROP 1 LASTPIN (-6300 2675) BN 7
J 0
(-6312 2683);
DISPLAY 0.489362 (-6312 2683);
PAINT GREEN (-6312 2683);
FORCEPROP 2 LAST CDS_LIB mstr_standard
J 0
(-6250 2675);
DISPLAY 0.723404 (-6250 2675);
PAINT MONO (-6250 2675);
DISPLAY INVISIBLE (-6250 2675);
FORCEPROP 1 LAST BODY_TYPE PLUMBING
J 0
(-6250 2725);
DISPLAY 0.872340 (-6250 2725);
PAINT GREEN (-6250 2725);
DISPLAY INVISIBLE (-6250 2725);
FORCEPROP 1 LAST HDL_TAP TRUE
J 0
(-5925 2550);
DISPLAY 0.872340 (-5925 2550);
DISPLAY INVISIBLE (-5925 2550);
FORCEPROP 1 LAST PATH I213
J 0
(-6252 2675);
DISPLAY 0.872340 (-6252 2675);
PAINT GREEN (-6252 2675);
DISPLAY INVISIBLE (-6252 2675);
FORCEADD TAP..1
(-6250 2625);
FORCEPROP 3 LASTPIN (-6300 2625) SIG_NAME M_B_CPU0_SB_DQ<6>
J 0
(-6290 2635);
DISPLAY 0.659574 (-6290 2635);
PAINT MONO (-6290 2635);
DISPLAY INVISIBLE (-6290 2635);
FORCEPROP 1 LASTPIN (-6300 2625) BN 6
J 0
(-6312 2633);
DISPLAY 0.489362 (-6312 2633);
PAINT GREEN (-6312 2633);
FORCEPROP 2 LAST CDS_LIB mstr_standard
J 0
(-6250 2625);
DISPLAY 0.723404 (-6250 2625);
PAINT MONO (-6250 2625);
DISPLAY INVISIBLE (-6250 2625);
FORCEPROP 1 LAST BODY_TYPE PLUMBING
J 0
(-6250 2675);
DISPLAY 0.872340 (-6250 2675);
PAINT GREEN (-6250 2675);
DISPLAY INVISIBLE (-6250 2675);
FORCEPROP 1 LAST HDL_TAP TRUE
J 0
(-5925 2500);
DISPLAY 0.872340 (-5925 2500);
DISPLAY INVISIBLE (-5925 2500);
FORCEPROP 1 LAST PATH I214
J 0
(-6252 2625);
DISPLAY 0.872340 (-6252 2625);
PAINT GREEN (-6252 2625);
DISPLAY INVISIBLE (-6252 2625);
FORCEADD TAP..1
(-6250 2725);
FORCEPROP 3 LASTPIN (-6300 2725) SIG_NAME M_B_CPU0_SB_DQ<8>
J 0
(-6290 2735);
DISPLAY 0.659574 (-6290 2735);
PAINT MONO (-6290 2735);
DISPLAY INVISIBLE (-6290 2735);
FORCEPROP 1 LASTPIN (-6300 2725) BN 8
J 0
(-6312 2733);
DISPLAY 0.489362 (-6312 2733);
PAINT GREEN (-6312 2733);
FORCEPROP 2 LAST CDS_LIB mstr_standard
J 0
(-6250 2725);
DISPLAY 0.723404 (-6250 2725);
PAINT MONO (-6250 2725);
DISPLAY INVISIBLE (-6250 2725);
FORCEPROP 1 LAST BODY_TYPE PLUMBING
J 0
(-6250 2775);
DISPLAY 0.872340 (-6250 2775);
PAINT GREEN (-6250 2775);
DISPLAY INVISIBLE (-6250 2775);
FORCEPROP 1 LAST HDL_TAP TRUE
J 0
(-5925 2600);
DISPLAY 0.872340 (-5925 2600);
DISPLAY INVISIBLE (-5925 2600);
FORCEPROP 1 LAST PATH I215
J 0
(-6252 2725);
DISPLAY 0.872340 (-6252 2725);
PAINT GREEN (-6252 2725);
DISPLAY INVISIBLE (-6252 2725);
FORCEADD TAP..1
(-6250 2775);
FORCEPROP 3 LASTPIN (-6300 2775) SIG_NAME M_B_CPU0_SB_DQ<9>
J 0
(-6290 2785);
DISPLAY 0.659574 (-6290 2785);
PAINT MONO (-6290 2785);
DISPLAY INVISIBLE (-6290 2785);
FORCEPROP 1 LASTPIN (-6300 2775) BN 9
J 0
(-6312 2783);
DISPLAY 0.489362 (-6312 2783);
PAINT GREEN (-6312 2783);
FORCEPROP 2 LAST CDS_LIB mstr_standard
J 0
(-6250 2775);
DISPLAY 0.723404 (-6250 2775);
PAINT MONO (-6250 2775);
DISPLAY INVISIBLE (-6250 2775);
FORCEPROP 1 LAST BODY_TYPE PLUMBING
J 0
(-6250 2825);
DISPLAY 0.872340 (-6250 2825);
PAINT GREEN (-6250 2825);
DISPLAY INVISIBLE (-6250 2825);
FORCEPROP 1 LAST HDL_TAP TRUE
J 0
(-5925 2650);
DISPLAY 0.872340 (-5925 2650);
DISPLAY INVISIBLE (-5925 2650);
FORCEPROP 1 LAST PATH I216
J 0
(-6252 2775);
DISPLAY 0.872340 (-6252 2775);
PAINT GREEN (-6252 2775);
DISPLAY INVISIBLE (-6252 2775);
FORCEADD TAP..1
(-6250 2825);
FORCEPROP 3 LASTPIN (-6300 2825) SIG_NAME M_B_CPU0_SB_DQ<10>
J 0
(-6290 2835);
DISPLAY 0.659574 (-6290 2835);
PAINT MONO (-6290 2835);
DISPLAY INVISIBLE (-6290 2835);
FORCEPROP 1 LASTPIN (-6300 2825) BN 10
J 0
(-6312 2833);
DISPLAY 0.489362 (-6312 2833);
PAINT GREEN (-6312 2833);
FORCEPROP 2 LAST CDS_LIB mstr_standard
J 0
(-6250 2825);
DISPLAY 0.723404 (-6250 2825);
PAINT MONO (-6250 2825);
DISPLAY INVISIBLE (-6250 2825);
FORCEPROP 1 LAST BODY_TYPE PLUMBING
J 0
(-6250 2875);
DISPLAY 0.872340 (-6250 2875);
PAINT GREEN (-6250 2875);
DISPLAY INVISIBLE (-6250 2875);
FORCEPROP 1 LAST HDL_TAP TRUE
J 0
(-5925 2700);
DISPLAY 0.872340 (-5925 2700);
DISPLAY INVISIBLE (-5925 2700);
FORCEPROP 1 LAST PATH I217
J 0
(-6252 2825);
DISPLAY 0.872340 (-6252 2825);
PAINT GREEN (-6252 2825);
DISPLAY INVISIBLE (-6252 2825);
FORCEADD TAP..1
(-6250 2875);
FORCEPROP 3 LASTPIN (-6300 2875) SIG_NAME M_B_CPU0_SB_DQ<11>
J 0
(-6290 2885);
DISPLAY 0.659574 (-6290 2885);
PAINT MONO (-6290 2885);
DISPLAY INVISIBLE (-6290 2885);
FORCEPROP 1 LASTPIN (-6300 2875) BN 11
J 0
(-6312 2883);
DISPLAY 0.489362 (-6312 2883);
PAINT GREEN (-6312 2883);
FORCEPROP 2 LAST CDS_LIB mstr_standard
J 0
(-6250 2875);
DISPLAY 0.723404 (-6250 2875);
PAINT MONO (-6250 2875);
DISPLAY INVISIBLE (-6250 2875);
FORCEPROP 1 LAST BODY_TYPE PLUMBING
J 0
(-6250 2925);
DISPLAY 0.872340 (-6250 2925);
PAINT GREEN (-6250 2925);
DISPLAY INVISIBLE (-6250 2925);
FORCEPROP 1 LAST HDL_TAP TRUE
J 0
(-5925 2750);
DISPLAY 0.872340 (-5925 2750);
DISPLAY INVISIBLE (-5925 2750);
FORCEPROP 1 LAST PATH I218
J 0
(-6252 2875);
DISPLAY 0.872340 (-6252 2875);
PAINT GREEN (-6252 2875);
DISPLAY INVISIBLE (-6252 2875);
FORCEADD TAP..1
(-6250 2925);
FORCEPROP 3 LASTPIN (-6300 2925) SIG_NAME M_B_CPU0_SB_DQ<12>
J 0
(-6290 2935);
DISPLAY 0.659574 (-6290 2935);
PAINT MONO (-6290 2935);
DISPLAY INVISIBLE (-6290 2935);
FORCEPROP 1 LASTPIN (-6300 2925) BN 12
J 0
(-6312 2933);
DISPLAY 0.489362 (-6312 2933);
PAINT GREEN (-6312 2933);
FORCEPROP 2 LAST CDS_LIB mstr_standard
J 0
(-6250 2925);
DISPLAY 0.723404 (-6250 2925);
PAINT MONO (-6250 2925);
DISPLAY INVISIBLE (-6250 2925);
FORCEPROP 1 LAST BODY_TYPE PLUMBING
J 0
(-6250 2975);
DISPLAY 0.872340 (-6250 2975);
PAINT GREEN (-6250 2975);
DISPLAY INVISIBLE (-6250 2975);
FORCEPROP 1 LAST HDL_TAP TRUE
J 0
(-5925 2800);
DISPLAY 0.872340 (-5925 2800);
DISPLAY INVISIBLE (-5925 2800);
FORCEPROP 1 LAST PATH I219
J 0
(-6252 2925);
DISPLAY 0.872340 (-6252 2925);
PAINT GREEN (-6252 2925);
DISPLAY INVISIBLE (-6252 2925);
FORCEADD TAP..1
(-6250 2975);
FORCEPROP 3 LASTPIN (-6300 2975) SIG_NAME M_B_CPU0_SB_DQ<13>
J 0
(-6290 2985);
DISPLAY 0.659574 (-6290 2985);
PAINT MONO (-6290 2985);
DISPLAY INVISIBLE (-6290 2985);
FORCEPROP 1 LASTPIN (-6300 2975) BN 13
J 0
(-6312 2983);
DISPLAY 0.489362 (-6312 2983);
PAINT GREEN (-6312 2983);
FORCEPROP 2 LAST CDS_LIB mstr_standard
J 0
(-6250 2975);
DISPLAY 0.723404 (-6250 2975);
PAINT MONO (-6250 2975);
DISPLAY INVISIBLE (-6250 2975);
FORCEPROP 1 LAST BODY_TYPE PLUMBING
J 0
(-6250 3025);
DISPLAY 0.872340 (-6250 3025);
PAINT GREEN (-6250 3025);
DISPLAY INVISIBLE (-6250 3025);
FORCEPROP 1 LAST HDL_TAP TRUE
J 0
(-5925 2850);
DISPLAY 0.872340 (-5925 2850);
DISPLAY INVISIBLE (-5925 2850);
FORCEPROP 1 LAST PATH I220
J 0
(-6252 2975);
DISPLAY 0.872340 (-6252 2975);
PAINT GREEN (-6252 2975);
DISPLAY INVISIBLE (-6252 2975);
FORCEADD TAP..1
(-6250 3075);
FORCEPROP 3 LASTPIN (-6300 3075) SIG_NAME M_B_CPU0_SB_DQ<15>
J 0
(-6290 3085);
DISPLAY 0.659574 (-6290 3085);
PAINT MONO (-6290 3085);
DISPLAY INVISIBLE (-6290 3085);
FORCEPROP 1 LASTPIN (-6300 3075) BN 15
J 0
(-6312 3083);
DISPLAY 0.489362 (-6312 3083);
PAINT GREEN (-6312 3083);
FORCEPROP 2 LAST CDS_LIB mstr_standard
J 0
(-6250 3075);
DISPLAY 0.723404 (-6250 3075);
PAINT MONO (-6250 3075);
DISPLAY INVISIBLE (-6250 3075);
FORCEPROP 1 LAST BODY_TYPE PLUMBING
J 0
(-6250 3125);
DISPLAY 0.872340 (-6250 3125);
PAINT GREEN (-6250 3125);
DISPLAY INVISIBLE (-6250 3125);
FORCEPROP 1 LAST HDL_TAP TRUE
J 0
(-5925 2950);
DISPLAY 0.872340 (-5925 2950);
DISPLAY INVISIBLE (-5925 2950);
FORCEPROP 1 LAST PATH I221
J 0
(-6252 3075);
DISPLAY 0.872340 (-6252 3075);
PAINT GREEN (-6252 3075);
DISPLAY INVISIBLE (-6252 3075);
FORCEADD TAP..1
(-6250 3025);
FORCEPROP 3 LASTPIN (-6300 3025) SIG_NAME M_B_CPU0_SB_DQ<14>
J 0
(-6290 3035);
DISPLAY 0.659574 (-6290 3035);
PAINT MONO (-6290 3035);
DISPLAY INVISIBLE (-6290 3035);
FORCEPROP 1 LASTPIN (-6300 3025) BN 14
J 0
(-6312 3033);
DISPLAY 0.489362 (-6312 3033);
PAINT GREEN (-6312 3033);
FORCEPROP 2 LAST CDS_LIB mstr_standard
J 0
(-6250 3025);
DISPLAY 0.723404 (-6250 3025);
PAINT MONO (-6250 3025);
DISPLAY INVISIBLE (-6250 3025);
FORCEPROP 1 LAST BODY_TYPE PLUMBING
J 0
(-6250 3075);
DISPLAY 0.872340 (-6250 3075);
PAINT GREEN (-6250 3075);
DISPLAY INVISIBLE (-6250 3075);
FORCEPROP 1 LAST HDL_TAP TRUE
J 0
(-5925 2900);
DISPLAY 0.872340 (-5925 2900);
DISPLAY INVISIBLE (-5925 2900);
FORCEPROP 1 LAST PATH I222
J 0
(-6252 3025);
DISPLAY 0.872340 (-6252 3025);
PAINT GREEN (-6252 3025);
DISPLAY INVISIBLE (-6252 3025);
FORCEADD TAP..1
(-6250 3225);
FORCEPROP 3 LASTPIN (-6300 3225) SIG_NAME M_B_CPU0_SB_DQ<18>
J 0
(-6290 3235);
DISPLAY 0.659574 (-6290 3235);
PAINT MONO (-6290 3235);
DISPLAY INVISIBLE (-6290 3235);
FORCEPROP 1 LASTPIN (-6300 3225) BN 18
J 0
(-6312 3233);
DISPLAY 0.489362 (-6312 3233);
PAINT GREEN (-6312 3233);
FORCEPROP 2 LAST CDS_LIB mstr_standard
J 0
(-6250 3225);
DISPLAY 0.723404 (-6250 3225);
PAINT MONO (-6250 3225);
DISPLAY INVISIBLE (-6250 3225);
FORCEPROP 1 LAST BODY_TYPE PLUMBING
J 0
(-6250 3275);
DISPLAY 0.872340 (-6250 3275);
PAINT GREEN (-6250 3275);
DISPLAY INVISIBLE (-6250 3275);
FORCEPROP 1 LAST HDL_TAP TRUE
J 0
(-5925 3100);
DISPLAY 0.872340 (-5925 3100);
DISPLAY INVISIBLE (-5925 3100);
FORCEPROP 1 LAST PATH I223
J 0
(-6252 3225);
DISPLAY 0.872340 (-6252 3225);
PAINT GREEN (-6252 3225);
DISPLAY INVISIBLE (-6252 3225);
FORCEADD TAP..1
(-6250 3175);
FORCEPROP 3 LASTPIN (-6300 3175) SIG_NAME M_B_CPU0_SB_DQ<17>
J 0
(-6290 3185);
DISPLAY 0.659574 (-6290 3185);
PAINT MONO (-6290 3185);
DISPLAY INVISIBLE (-6290 3185);
FORCEPROP 1 LASTPIN (-6300 3175) BN 17
J 0
(-6312 3183);
DISPLAY 0.489362 (-6312 3183);
PAINT GREEN (-6312 3183);
FORCEPROP 2 LAST CDS_LIB mstr_standard
J 0
(-6250 3175);
DISPLAY 0.723404 (-6250 3175);
PAINT MONO (-6250 3175);
DISPLAY INVISIBLE (-6250 3175);
FORCEPROP 1 LAST BODY_TYPE PLUMBING
J 0
(-6250 3225);
DISPLAY 0.872340 (-6250 3225);
PAINT GREEN (-6250 3225);
DISPLAY INVISIBLE (-6250 3225);
FORCEPROP 1 LAST HDL_TAP TRUE
J 0
(-5925 3050);
DISPLAY 0.872340 (-5925 3050);
DISPLAY INVISIBLE (-5925 3050);
FORCEPROP 1 LAST PATH I224
J 0
(-6252 3175);
DISPLAY 0.872340 (-6252 3175);
PAINT GREEN (-6252 3175);
DISPLAY INVISIBLE (-6252 3175);
FORCEADD TAP..1
(-6250 3125);
FORCEPROP 3 LASTPIN (-6300 3125) SIG_NAME M_B_CPU0_SB_DQ<16>
J 0
(-6290 3135);
DISPLAY 0.659574 (-6290 3135);
PAINT MONO (-6290 3135);
DISPLAY INVISIBLE (-6290 3135);
FORCEPROP 1 LASTPIN (-6300 3125) BN 16
J 0
(-6312 3133);
DISPLAY 0.489362 (-6312 3133);
PAINT GREEN (-6312 3133);
FORCEPROP 2 LAST CDS_LIB mstr_standard
J 0
(-6250 3125);
DISPLAY 0.723404 (-6250 3125);
PAINT MONO (-6250 3125);
DISPLAY INVISIBLE (-6250 3125);
FORCEPROP 1 LAST BODY_TYPE PLUMBING
J 0
(-6250 3175);
DISPLAY 0.872340 (-6250 3175);
PAINT GREEN (-6250 3175);
DISPLAY INVISIBLE (-6250 3175);
FORCEPROP 1 LAST HDL_TAP TRUE
J 0
(-5925 3000);
DISPLAY 0.872340 (-5925 3000);
DISPLAY INVISIBLE (-5925 3000);
FORCEPROP 1 LAST PATH I225
J 0
(-6252 3125);
DISPLAY 0.872340 (-6252 3125);
PAINT GREEN (-6252 3125);
DISPLAY INVISIBLE (-6252 3125);
FORCEADD TAP..1
(-6250 3375);
FORCEPROP 3 LASTPIN (-6300 3375) SIG_NAME M_B_CPU0_SB_DQ<21>
J 0
(-6290 3385);
DISPLAY 0.659574 (-6290 3385);
PAINT MONO (-6290 3385);
DISPLAY INVISIBLE (-6290 3385);
FORCEPROP 1 LASTPIN (-6300 3375) BN 21
J 0
(-6312 3383);
DISPLAY 0.489362 (-6312 3383);
PAINT GREEN (-6312 3383);
FORCEPROP 2 LAST CDS_LIB mstr_standard
J 0
(-6250 3375);
DISPLAY 0.723404 (-6250 3375);
PAINT MONO (-6250 3375);
DISPLAY INVISIBLE (-6250 3375);
FORCEPROP 1 LAST BODY_TYPE PLUMBING
J 0
(-6250 3425);
DISPLAY 0.872340 (-6250 3425);
PAINT GREEN (-6250 3425);
DISPLAY INVISIBLE (-6250 3425);
FORCEPROP 1 LAST HDL_TAP TRUE
J 0
(-5925 3250);
DISPLAY 0.872340 (-5925 3250);
DISPLAY INVISIBLE (-5925 3250);
FORCEPROP 1 LAST PATH I226
J 0
(-6252 3375);
DISPLAY 0.872340 (-6252 3375);
PAINT GREEN (-6252 3375);
DISPLAY INVISIBLE (-6252 3375);
FORCEADD TAP..1
(-6250 3425);
FORCEPROP 3 LASTPIN (-6300 3425) SIG_NAME M_B_CPU0_SB_DQ<22>
J 0
(-6290 3435);
DISPLAY 0.659574 (-6290 3435);
PAINT MONO (-6290 3435);
DISPLAY INVISIBLE (-6290 3435);
FORCEPROP 1 LASTPIN (-6300 3425) BN 22
J 0
(-6312 3433);
DISPLAY 0.489362 (-6312 3433);
PAINT GREEN (-6312 3433);
FORCEPROP 2 LAST CDS_LIB mstr_standard
J 0
(-6250 3425);
DISPLAY 0.723404 (-6250 3425);
PAINT MONO (-6250 3425);
DISPLAY INVISIBLE (-6250 3425);
FORCEPROP 1 LAST BODY_TYPE PLUMBING
J 0
(-6250 3475);
DISPLAY 0.872340 (-6250 3475);
PAINT GREEN (-6250 3475);
DISPLAY INVISIBLE (-6250 3475);
FORCEPROP 1 LAST HDL_TAP TRUE
J 0
(-5925 3300);
DISPLAY 0.872340 (-5925 3300);
DISPLAY INVISIBLE (-5925 3300);
FORCEPROP 1 LAST PATH I227
J 0
(-6252 3425);
DISPLAY 0.872340 (-6252 3425);
PAINT GREEN (-6252 3425);
DISPLAY INVISIBLE (-6252 3425);
FORCEADD TAP..1
(-6250 3325);
FORCEPROP 3 LASTPIN (-6300 3325) SIG_NAME M_B_CPU0_SB_DQ<20>
J 0
(-6290 3335);
DISPLAY 0.659574 (-6290 3335);
PAINT MONO (-6290 3335);
DISPLAY INVISIBLE (-6290 3335);
FORCEPROP 1 LASTPIN (-6300 3325) BN 20
J 0
(-6312 3333);
DISPLAY 0.489362 (-6312 3333);
PAINT GREEN (-6312 3333);
FORCEPROP 2 LAST CDS_LIB mstr_standard
J 0
(-6250 3325);
DISPLAY 0.723404 (-6250 3325);
PAINT MONO (-6250 3325);
DISPLAY INVISIBLE (-6250 3325);
FORCEPROP 1 LAST BODY_TYPE PLUMBING
J 0
(-6250 3375);
DISPLAY 0.872340 (-6250 3375);
PAINT GREEN (-6250 3375);
DISPLAY INVISIBLE (-6250 3375);
FORCEPROP 1 LAST HDL_TAP TRUE
J 0
(-5925 3200);
DISPLAY 0.872340 (-5925 3200);
DISPLAY INVISIBLE (-5925 3200);
FORCEPROP 1 LAST PATH I228
J 0
(-6252 3325);
DISPLAY 0.872340 (-6252 3325);
PAINT GREEN (-6252 3325);
DISPLAY INVISIBLE (-6252 3325);
FORCEADD TAP..1
(-6250 3475);
FORCEPROP 3 LASTPIN (-6300 3475) SIG_NAME M_B_CPU0_SB_DQ<23>
J 0
(-6290 3485);
DISPLAY 0.659574 (-6290 3485);
PAINT MONO (-6290 3485);
DISPLAY INVISIBLE (-6290 3485);
FORCEPROP 1 LASTPIN (-6300 3475) BN 23
J 0
(-6312 3483);
DISPLAY 0.489362 (-6312 3483);
PAINT GREEN (-6312 3483);
FORCEPROP 2 LAST CDS_LIB mstr_standard
J 0
(-6250 3475);
DISPLAY 0.723404 (-6250 3475);
PAINT MONO (-6250 3475);
DISPLAY INVISIBLE (-6250 3475);
FORCEPROP 1 LAST BODY_TYPE PLUMBING
J 0
(-6250 3525);
DISPLAY 0.872340 (-6250 3525);
PAINT GREEN (-6250 3525);
DISPLAY INVISIBLE (-6250 3525);
FORCEPROP 1 LAST HDL_TAP TRUE
J 0
(-5925 3350);
DISPLAY 0.872340 (-5925 3350);
DISPLAY INVISIBLE (-5925 3350);
FORCEPROP 1 LAST PATH I229
J 0
(-6252 3475);
DISPLAY 0.872340 (-6252 3475);
PAINT GREEN (-6252 3475);
DISPLAY INVISIBLE (-6252 3475);
FORCEADD TAP..1
(-6250 3275);
FORCEPROP 3 LASTPIN (-6300 3275) SIG_NAME M_B_CPU0_SB_DQ<19>
J 0
(-6290 3285);
DISPLAY 0.659574 (-6290 3285);
PAINT MONO (-6290 3285);
DISPLAY INVISIBLE (-6290 3285);
FORCEPROP 1 LASTPIN (-6300 3275) BN 19
J 0
(-6312 3283);
DISPLAY 0.489362 (-6312 3283);
PAINT GREEN (-6312 3283);
FORCEPROP 2 LAST CDS_LIB mstr_standard
J 0
(-6250 3275);
DISPLAY 0.723404 (-6250 3275);
PAINT MONO (-6250 3275);
DISPLAY INVISIBLE (-6250 3275);
FORCEPROP 1 LAST BODY_TYPE PLUMBING
J 0
(-6250 3325);
DISPLAY 0.872340 (-6250 3325);
PAINT GREEN (-6250 3325);
DISPLAY INVISIBLE (-6250 3325);
FORCEPROP 1 LAST HDL_TAP TRUE
J 0
(-5925 3150);
DISPLAY 0.872340 (-5925 3150);
DISPLAY INVISIBLE (-5925 3150);
FORCEPROP 1 LAST PATH I230
J 0
(-6252 3275);
DISPLAY 0.872340 (-6252 3275);
PAINT GREEN (-6252 3275);
DISPLAY INVISIBLE (-6252 3275);
FORCEADD TAP..1
(-6250 3625);
FORCEPROP 3 LASTPIN (-6300 3625) SIG_NAME M_B_CPU0_SB_DQ<26>
J 0
(-6290 3635);
DISPLAY 0.659574 (-6290 3635);
PAINT MONO (-6290 3635);
DISPLAY INVISIBLE (-6290 3635);
FORCEPROP 1 LASTPIN (-6300 3625) BN 26
J 0
(-6312 3633);
DISPLAY 0.489362 (-6312 3633);
PAINT GREEN (-6312 3633);
FORCEPROP 2 LAST CDS_LIB mstr_standard
J 0
(-6250 3625);
DISPLAY 0.723404 (-6250 3625);
PAINT MONO (-6250 3625);
DISPLAY INVISIBLE (-6250 3625);
FORCEPROP 1 LAST BODY_TYPE PLUMBING
J 0
(-6250 3675);
DISPLAY 0.872340 (-6250 3675);
PAINT GREEN (-6250 3675);
DISPLAY INVISIBLE (-6250 3675);
FORCEPROP 1 LAST HDL_TAP TRUE
J 0
(-5925 3500);
DISPLAY 0.872340 (-5925 3500);
DISPLAY INVISIBLE (-5925 3500);
FORCEPROP 1 LAST PATH I231
J 0
(-6252 3625);
DISPLAY 0.872340 (-6252 3625);
PAINT GREEN (-6252 3625);
DISPLAY INVISIBLE (-6252 3625);
FORCEADD TAP..1
(-6250 3675);
FORCEPROP 3 LASTPIN (-6300 3675) SIG_NAME M_B_CPU0_SB_DQ<27>
J 0
(-6290 3685);
DISPLAY 0.659574 (-6290 3685);
PAINT MONO (-6290 3685);
DISPLAY INVISIBLE (-6290 3685);
FORCEPROP 1 LASTPIN (-6300 3675) BN 27
J 0
(-6312 3683);
DISPLAY 0.489362 (-6312 3683);
PAINT GREEN (-6312 3683);
FORCEPROP 2 LAST CDS_LIB mstr_standard
J 0
(-6250 3675);
DISPLAY 0.723404 (-6250 3675);
PAINT MONO (-6250 3675);
DISPLAY INVISIBLE (-6250 3675);
FORCEPROP 1 LAST BODY_TYPE PLUMBING
J 0
(-6250 3725);
DISPLAY 0.872340 (-6250 3725);
PAINT GREEN (-6250 3725);
DISPLAY INVISIBLE (-6250 3725);
FORCEPROP 1 LAST HDL_TAP TRUE
J 0
(-5925 3550);
DISPLAY 0.872340 (-5925 3550);
DISPLAY INVISIBLE (-5925 3550);
FORCEPROP 1 LAST PATH I232
J 0
(-6252 3675);
DISPLAY 0.872340 (-6252 3675);
PAINT GREEN (-6252 3675);
DISPLAY INVISIBLE (-6252 3675);
FORCEADD TAP..1
(-6250 3575);
FORCEPROP 3 LASTPIN (-6300 3575) SIG_NAME M_B_CPU0_SB_DQ<25>
J 0
(-6290 3585);
DISPLAY 0.659574 (-6290 3585);
PAINT MONO (-6290 3585);
DISPLAY INVISIBLE (-6290 3585);
FORCEPROP 1 LASTPIN (-6300 3575) BN 25
J 0
(-6312 3583);
DISPLAY 0.489362 (-6312 3583);
PAINT GREEN (-6312 3583);
FORCEPROP 2 LAST CDS_LIB mstr_standard
J 0
(-6250 3575);
DISPLAY 0.723404 (-6250 3575);
PAINT MONO (-6250 3575);
DISPLAY INVISIBLE (-6250 3575);
FORCEPROP 1 LAST BODY_TYPE PLUMBING
J 0
(-6250 3625);
DISPLAY 0.872340 (-6250 3625);
PAINT GREEN (-6250 3625);
DISPLAY INVISIBLE (-6250 3625);
FORCEPROP 1 LAST HDL_TAP TRUE
J 0
(-5925 3450);
DISPLAY 0.872340 (-5925 3450);
DISPLAY INVISIBLE (-5925 3450);
FORCEPROP 1 LAST PATH I233
J 0
(-6252 3575);
DISPLAY 0.872340 (-6252 3575);
PAINT GREEN (-6252 3575);
DISPLAY INVISIBLE (-6252 3575);
FORCEADD TAP..1
(-6250 3725);
FORCEPROP 3 LASTPIN (-6300 3725) SIG_NAME M_B_CPU0_SB_DQ<28>
J 0
(-6290 3735);
DISPLAY 0.659574 (-6290 3735);
PAINT MONO (-6290 3735);
DISPLAY INVISIBLE (-6290 3735);
FORCEPROP 1 LASTPIN (-6300 3725) BN 28
J 0
(-6312 3733);
DISPLAY 0.489362 (-6312 3733);
PAINT GREEN (-6312 3733);
FORCEPROP 2 LAST CDS_LIB mstr_standard
J 0
(-6250 3725);
DISPLAY 0.723404 (-6250 3725);
PAINT MONO (-6250 3725);
DISPLAY INVISIBLE (-6250 3725);
FORCEPROP 1 LAST BODY_TYPE PLUMBING
J 0
(-6250 3775);
DISPLAY 0.872340 (-6250 3775);
PAINT GREEN (-6250 3775);
DISPLAY INVISIBLE (-6250 3775);
FORCEPROP 1 LAST HDL_TAP TRUE
J 0
(-5925 3600);
DISPLAY 0.872340 (-5925 3600);
DISPLAY INVISIBLE (-5925 3600);
FORCEPROP 1 LAST PATH I234
J 0
(-6252 3725);
DISPLAY 0.872340 (-6252 3725);
PAINT GREEN (-6252 3725);
DISPLAY INVISIBLE (-6252 3725);
FORCEADD TAP..1
(-6250 3525);
FORCEPROP 3 LASTPIN (-6300 3525) SIG_NAME M_B_CPU0_SB_DQ<24>
J 0
(-6290 3535);
DISPLAY 0.659574 (-6290 3535);
PAINT MONO (-6290 3535);
DISPLAY INVISIBLE (-6290 3535);
FORCEPROP 1 LASTPIN (-6300 3525) BN 24
J 0
(-6312 3533);
DISPLAY 0.489362 (-6312 3533);
PAINT GREEN (-6312 3533);
FORCEPROP 2 LAST CDS_LIB mstr_standard
J 0
(-6250 3525);
DISPLAY 0.723404 (-6250 3525);
PAINT MONO (-6250 3525);
DISPLAY INVISIBLE (-6250 3525);
FORCEPROP 1 LAST BODY_TYPE PLUMBING
J 0
(-6250 3575);
DISPLAY 0.872340 (-6250 3575);
PAINT GREEN (-6250 3575);
DISPLAY INVISIBLE (-6250 3575);
FORCEPROP 1 LAST HDL_TAP TRUE
J 0
(-5925 3400);
DISPLAY 0.872340 (-5925 3400);
DISPLAY INVISIBLE (-5925 3400);
FORCEPROP 1 LAST PATH I235
J 0
(-6252 3525);
DISPLAY 0.872340 (-6252 3525);
PAINT GREEN (-6252 3525);
DISPLAY INVISIBLE (-6252 3525);
FORCEADD TAP..1
(-6250 3975);
FORCEPROP 3 LASTPIN (-6300 3975) SIG_NAME M_B_CPU0_SA_DQ<0>
J 0
(-6290 3985);
DISPLAY 0.659574 (-6290 3985);
PAINT MONO (-6290 3985);
DISPLAY INVISIBLE (-6290 3985);
FORCEPROP 1 LASTPIN (-6300 3975) BN 0
J 0
(-6312 3983);
DISPLAY 0.489362 (-6312 3983);
PAINT GREEN (-6312 3983);
FORCEPROP 2 LAST CDS_LIB mstr_standard
J 0
(-6250 3975);
DISPLAY 0.723404 (-6250 3975);
PAINT MONO (-6250 3975);
DISPLAY INVISIBLE (-6250 3975);
FORCEPROP 1 LAST BODY_TYPE PLUMBING
J 0
(-6250 4025);
DISPLAY 0.872340 (-6250 4025);
PAINT GREEN (-6250 4025);
DISPLAY INVISIBLE (-6250 4025);
FORCEPROP 1 LAST HDL_TAP TRUE
J 0
(-5925 3850);
DISPLAY 0.872340 (-5925 3850);
DISPLAY INVISIBLE (-5925 3850);
FORCEPROP 1 LAST PATH I236
J 0
(-6252 3975);
DISPLAY 0.872340 (-6252 3975);
PAINT GREEN (-6252 3975);
DISPLAY INVISIBLE (-6252 3975);
FORCEADD TAP..1
(-6250 3825);
FORCEPROP 3 LASTPIN (-6300 3825) SIG_NAME M_B_CPU0_SB_DQ<30>
J 0
(-6290 3835);
DISPLAY 0.659574 (-6290 3835);
PAINT MONO (-6290 3835);
DISPLAY INVISIBLE (-6290 3835);
FORCEPROP 1 LASTPIN (-6300 3825) BN 30
J 0
(-6312 3833);
DISPLAY 0.489362 (-6312 3833);
PAINT GREEN (-6312 3833);
FORCEPROP 2 LAST CDS_LIB mstr_standard
J 0
(-6250 3825);
DISPLAY 0.723404 (-6250 3825);
PAINT MONO (-6250 3825);
DISPLAY INVISIBLE (-6250 3825);
FORCEPROP 1 LAST BODY_TYPE PLUMBING
J 0
(-6250 3875);
DISPLAY 0.872340 (-6250 3875);
PAINT GREEN (-6250 3875);
DISPLAY INVISIBLE (-6250 3875);
FORCEPROP 1 LAST HDL_TAP TRUE
J 0
(-5925 3700);
DISPLAY 0.872340 (-5925 3700);
DISPLAY INVISIBLE (-5925 3700);
FORCEPROP 1 LAST PATH I237
J 0
(-6252 3825);
DISPLAY 0.872340 (-6252 3825);
PAINT GREEN (-6252 3825);
DISPLAY INVISIBLE (-6252 3825);
FORCEADD TAP..1
(-6250 3875);
FORCEPROP 3 LASTPIN (-6300 3875) SIG_NAME M_B_CPU0_SB_DQ<31>
J 0
(-6290 3885);
DISPLAY 0.659574 (-6290 3885);
PAINT MONO (-6290 3885);
DISPLAY INVISIBLE (-6290 3885);
FORCEPROP 1 LASTPIN (-6300 3875) BN 31
J 0
(-6312 3883);
DISPLAY 0.489362 (-6312 3883);
PAINT GREEN (-6312 3883);
FORCEPROP 2 LAST CDS_LIB mstr_standard
J 0
(-6250 3875);
DISPLAY 0.723404 (-6250 3875);
PAINT MONO (-6250 3875);
DISPLAY INVISIBLE (-6250 3875);
FORCEPROP 1 LAST BODY_TYPE PLUMBING
J 0
(-6250 3925);
DISPLAY 0.872340 (-6250 3925);
PAINT GREEN (-6250 3925);
DISPLAY INVISIBLE (-6250 3925);
FORCEPROP 1 LAST HDL_TAP TRUE
J 0
(-5925 3750);
DISPLAY 0.872340 (-5925 3750);
DISPLAY INVISIBLE (-5925 3750);
FORCEPROP 1 LAST PATH I238
J 0
(-6252 3875);
DISPLAY 0.872340 (-6252 3875);
PAINT GREEN (-6252 3875);
DISPLAY INVISIBLE (-6252 3875);
FORCEADD TAP..1
(-6250 3775);
FORCEPROP 3 LASTPIN (-6300 3775) SIG_NAME M_B_CPU0_SB_DQ<29>
J 0
(-6290 3785);
DISPLAY 0.659574 (-6290 3785);
PAINT MONO (-6290 3785);
DISPLAY INVISIBLE (-6290 3785);
FORCEPROP 1 LASTPIN (-6300 3775) BN 29
J 0
(-6312 3783);
DISPLAY 0.489362 (-6312 3783);
PAINT GREEN (-6312 3783);
FORCEPROP 2 LAST CDS_LIB mstr_standard
J 0
(-6250 3775);
DISPLAY 0.723404 (-6250 3775);
PAINT MONO (-6250 3775);
DISPLAY INVISIBLE (-6250 3775);
FORCEPROP 1 LAST BODY_TYPE PLUMBING
J 0
(-6250 3825);
DISPLAY 0.872340 (-6250 3825);
PAINT GREEN (-6250 3825);
DISPLAY INVISIBLE (-6250 3825);
FORCEPROP 1 LAST HDL_TAP TRUE
J 0
(-5925 3650);
DISPLAY 0.872340 (-5925 3650);
DISPLAY INVISIBLE (-5925 3650);
FORCEPROP 1 LAST PATH I239
J 0
(-6252 3775);
DISPLAY 0.872340 (-6252 3775);
PAINT GREEN (-6252 3775);
DISPLAY INVISIBLE (-6252 3775);
FORCEADD TAP..1
(-6250 4075);
FORCEPROP 3 LASTPIN (-6300 4075) SIG_NAME M_B_CPU0_SA_DQ<2>
J 0
(-6290 4085);
DISPLAY 0.659574 (-6290 4085);
PAINT MONO (-6290 4085);
DISPLAY INVISIBLE (-6290 4085);
FORCEPROP 1 LASTPIN (-6300 4075) BN 2
J 0
(-6312 4083);
DISPLAY 0.489362 (-6312 4083);
PAINT GREEN (-6312 4083);
FORCEPROP 2 LAST CDS_LIB mstr_standard
J 0
(-6250 4075);
DISPLAY 0.723404 (-6250 4075);
PAINT MONO (-6250 4075);
DISPLAY INVISIBLE (-6250 4075);
FORCEPROP 1 LAST BODY_TYPE PLUMBING
J 0
(-6250 4125);
DISPLAY 0.872340 (-6250 4125);
PAINT GREEN (-6250 4125);
DISPLAY INVISIBLE (-6250 4125);
FORCEPROP 1 LAST HDL_TAP TRUE
J 0
(-5925 3950);
DISPLAY 0.872340 (-5925 3950);
DISPLAY INVISIBLE (-5925 3950);
FORCEPROP 1 LAST PATH I240
J 0
(-6252 4075);
DISPLAY 0.872340 (-6252 4075);
PAINT GREEN (-6252 4075);
DISPLAY INVISIBLE (-6252 4075);
FORCEADD TAP..1
(-6250 4025);
FORCEPROP 3 LASTPIN (-6300 4025) SIG_NAME M_B_CPU0_SA_DQ<1>
J 0
(-6290 4035);
DISPLAY 0.659574 (-6290 4035);
PAINT MONO (-6290 4035);
DISPLAY INVISIBLE (-6290 4035);
FORCEPROP 1 LASTPIN (-6300 4025) BN 1
J 0
(-6312 4033);
DISPLAY 0.489362 (-6312 4033);
PAINT GREEN (-6312 4033);
FORCEPROP 2 LAST CDS_LIB mstr_standard
J 0
(-6250 4025);
DISPLAY 0.723404 (-6250 4025);
PAINT MONO (-6250 4025);
DISPLAY INVISIBLE (-6250 4025);
FORCEPROP 1 LAST BODY_TYPE PLUMBING
J 0
(-6250 4075);
DISPLAY 0.872340 (-6250 4075);
PAINT GREEN (-6250 4075);
DISPLAY INVISIBLE (-6250 4075);
FORCEPROP 1 LAST HDL_TAP TRUE
J 0
(-5925 3900);
DISPLAY 0.872340 (-5925 3900);
DISPLAY INVISIBLE (-5925 3900);
FORCEPROP 1 LAST PATH I241
J 0
(-6252 4025);
DISPLAY 0.872340 (-6252 4025);
PAINT GREEN (-6252 4025);
DISPLAY INVISIBLE (-6252 4025);
FORCEADD TAP..1
(-6250 4125);
FORCEPROP 3 LASTPIN (-6300 4125) SIG_NAME M_B_CPU0_SA_DQ<3>
J 0
(-6290 4135);
DISPLAY 0.659574 (-6290 4135);
PAINT MONO (-6290 4135);
DISPLAY INVISIBLE (-6290 4135);
FORCEPROP 1 LASTPIN (-6300 4125) BN 3
J 0
(-6312 4133);
DISPLAY 0.489362 (-6312 4133);
PAINT GREEN (-6312 4133);
FORCEPROP 2 LAST CDS_LIB mstr_standard
J 0
(-6250 4125);
DISPLAY 0.723404 (-6250 4125);
PAINT MONO (-6250 4125);
DISPLAY INVISIBLE (-6250 4125);
FORCEPROP 1 LAST BODY_TYPE PLUMBING
J 0
(-6250 4175);
DISPLAY 0.872340 (-6250 4175);
PAINT GREEN (-6250 4175);
DISPLAY INVISIBLE (-6250 4175);
FORCEPROP 1 LAST HDL_TAP TRUE
J 0
(-5925 4000);
DISPLAY 0.872340 (-5925 4000);
DISPLAY INVISIBLE (-5925 4000);
FORCEPROP 1 LAST PATH I242
J 0
(-6252 4125);
DISPLAY 0.872340 (-6252 4125);
PAINT GREEN (-6252 4125);
DISPLAY INVISIBLE (-6252 4125);
FORCEADD TAP..1
(-6250 4175);
FORCEPROP 3 LASTPIN (-6300 4175) SIG_NAME M_B_CPU0_SA_DQ<4>
J 0
(-6290 4185);
DISPLAY 0.659574 (-6290 4185);
PAINT MONO (-6290 4185);
DISPLAY INVISIBLE (-6290 4185);
FORCEPROP 1 LASTPIN (-6300 4175) BN 4
J 0
(-6312 4183);
DISPLAY 0.489362 (-6312 4183);
PAINT GREEN (-6312 4183);
FORCEPROP 2 LAST CDS_LIB mstr_standard
J 0
(-6250 4175);
DISPLAY 0.723404 (-6250 4175);
PAINT MONO (-6250 4175);
DISPLAY INVISIBLE (-6250 4175);
FORCEPROP 1 LAST BODY_TYPE PLUMBING
J 0
(-6250 4225);
DISPLAY 0.872340 (-6250 4225);
PAINT GREEN (-6250 4225);
DISPLAY INVISIBLE (-6250 4225);
FORCEPROP 1 LAST HDL_TAP TRUE
J 0
(-5925 4050);
DISPLAY 0.872340 (-5925 4050);
DISPLAY INVISIBLE (-5925 4050);
FORCEPROP 1 LAST PATH I243
J 0
(-6252 4175);
DISPLAY 0.872340 (-6252 4175);
PAINT GREEN (-6252 4175);
DISPLAY INVISIBLE (-6252 4175);
FORCEADD TAP..1
(-6250 4225);
FORCEPROP 3 LASTPIN (-6300 4225) SIG_NAME M_B_CPU0_SA_DQ<5>
J 0
(-6290 4235);
DISPLAY 0.659574 (-6290 4235);
PAINT MONO (-6290 4235);
DISPLAY INVISIBLE (-6290 4235);
FORCEPROP 1 LASTPIN (-6300 4225) BN 5
J 0
(-6312 4233);
DISPLAY 0.489362 (-6312 4233);
PAINT GREEN (-6312 4233);
FORCEPROP 2 LAST CDS_LIB mstr_standard
J 0
(-6250 4225);
DISPLAY 0.723404 (-6250 4225);
PAINT MONO (-6250 4225);
DISPLAY INVISIBLE (-6250 4225);
FORCEPROP 1 LAST BODY_TYPE PLUMBING
J 0
(-6250 4275);
DISPLAY 0.872340 (-6250 4275);
PAINT GREEN (-6250 4275);
DISPLAY INVISIBLE (-6250 4275);
FORCEPROP 1 LAST HDL_TAP TRUE
J 0
(-5925 4100);
DISPLAY 0.872340 (-5925 4100);
DISPLAY INVISIBLE (-5925 4100);
FORCEPROP 1 LAST PATH I244
J 0
(-6252 4225);
DISPLAY 0.872340 (-6252 4225);
PAINT GREEN (-6252 4225);
DISPLAY INVISIBLE (-6252 4225);
FORCEADD TAP..1
(-6250 4325);
FORCEPROP 3 LASTPIN (-6300 4325) SIG_NAME M_B_CPU0_SA_DQ<7>
J 0
(-6290 4335);
DISPLAY 0.659574 (-6290 4335);
PAINT MONO (-6290 4335);
DISPLAY INVISIBLE (-6290 4335);
FORCEPROP 1 LASTPIN (-6300 4325) BN 7
J 0
(-6312 4333);
DISPLAY 0.489362 (-6312 4333);
PAINT GREEN (-6312 4333);
FORCEPROP 2 LAST CDS_LIB mstr_standard
J 0
(-6250 4325);
DISPLAY 0.723404 (-6250 4325);
PAINT MONO (-6250 4325);
DISPLAY INVISIBLE (-6250 4325);
FORCEPROP 1 LAST BODY_TYPE PLUMBING
J 0
(-6250 4375);
DISPLAY 0.872340 (-6250 4375);
PAINT GREEN (-6250 4375);
DISPLAY INVISIBLE (-6250 4375);
FORCEPROP 1 LAST HDL_TAP TRUE
J 0
(-5925 4200);
DISPLAY 0.872340 (-5925 4200);
DISPLAY INVISIBLE (-5925 4200);
FORCEPROP 1 LAST PATH I245
J 0
(-6252 4325);
DISPLAY 0.872340 (-6252 4325);
PAINT GREEN (-6252 4325);
DISPLAY INVISIBLE (-6252 4325);
FORCEADD TAP..1
(-6250 4275);
FORCEPROP 3 LASTPIN (-6300 4275) SIG_NAME M_B_CPU0_SA_DQ<6>
J 0
(-6290 4285);
DISPLAY 0.659574 (-6290 4285);
PAINT MONO (-6290 4285);
DISPLAY INVISIBLE (-6290 4285);
FORCEPROP 1 LASTPIN (-6300 4275) BN 6
J 0
(-6312 4283);
DISPLAY 0.489362 (-6312 4283);
PAINT GREEN (-6312 4283);
FORCEPROP 2 LAST CDS_LIB mstr_standard
J 0
(-6250 4275);
DISPLAY 0.723404 (-6250 4275);
PAINT MONO (-6250 4275);
DISPLAY INVISIBLE (-6250 4275);
FORCEPROP 1 LAST BODY_TYPE PLUMBING
J 0
(-6250 4325);
DISPLAY 0.872340 (-6250 4325);
PAINT GREEN (-6250 4325);
DISPLAY INVISIBLE (-6250 4325);
FORCEPROP 1 LAST HDL_TAP TRUE
J 0
(-5925 4150);
DISPLAY 0.872340 (-5925 4150);
DISPLAY INVISIBLE (-5925 4150);
FORCEPROP 1 LAST PATH I246
J 0
(-6252 4275);
DISPLAY 0.872340 (-6252 4275);
PAINT GREEN (-6252 4275);
DISPLAY INVISIBLE (-6252 4275);
FORCEADD TAP..1
(-6250 4375);
FORCEPROP 3 LASTPIN (-6300 4375) SIG_NAME M_B_CPU0_SA_DQ<8>
J 0
(-6290 4385);
DISPLAY 0.659574 (-6290 4385);
PAINT MONO (-6290 4385);
DISPLAY INVISIBLE (-6290 4385);
FORCEPROP 1 LASTPIN (-6300 4375) BN 8
J 0
(-6312 4383);
DISPLAY 0.489362 (-6312 4383);
PAINT GREEN (-6312 4383);
FORCEPROP 2 LAST CDS_LIB mstr_standard
J 0
(-6250 4375);
DISPLAY 0.723404 (-6250 4375);
PAINT MONO (-6250 4375);
DISPLAY INVISIBLE (-6250 4375);
FORCEPROP 1 LAST BODY_TYPE PLUMBING
J 0
(-6250 4425);
DISPLAY 0.872340 (-6250 4425);
PAINT GREEN (-6250 4425);
DISPLAY INVISIBLE (-6250 4425);
FORCEPROP 1 LAST HDL_TAP TRUE
J 0
(-5925 4250);
DISPLAY 0.872340 (-5925 4250);
DISPLAY INVISIBLE (-5925 4250);
FORCEPROP 1 LAST PATH I247
J 0
(-6252 4375);
DISPLAY 0.872340 (-6252 4375);
PAINT GREEN (-6252 4375);
DISPLAY INVISIBLE (-6252 4375);
FORCEADD TAP..1
(-6250 4425);
FORCEPROP 3 LASTPIN (-6300 4425) SIG_NAME M_B_CPU0_SA_DQ<9>
J 0
(-6290 4435);
DISPLAY 0.659574 (-6290 4435);
PAINT MONO (-6290 4435);
DISPLAY INVISIBLE (-6290 4435);
FORCEPROP 1 LASTPIN (-6300 4425) BN 9
J 0
(-6312 4433);
DISPLAY 0.489362 (-6312 4433);
PAINT GREEN (-6312 4433);
FORCEPROP 2 LAST CDS_LIB mstr_standard
J 0
(-6250 4425);
DISPLAY 0.723404 (-6250 4425);
PAINT MONO (-6250 4425);
DISPLAY INVISIBLE (-6250 4425);
FORCEPROP 1 LAST BODY_TYPE PLUMBING
J 0
(-6250 4475);
DISPLAY 0.872340 (-6250 4475);
PAINT GREEN (-6250 4475);
DISPLAY INVISIBLE (-6250 4475);
FORCEPROP 1 LAST HDL_TAP TRUE
J 0
(-5925 4300);
DISPLAY 0.872340 (-5925 4300);
DISPLAY INVISIBLE (-5925 4300);
FORCEPROP 1 LAST PATH I248
J 0
(-6252 4425);
DISPLAY 0.872340 (-6252 4425);
PAINT GREEN (-6252 4425);
DISPLAY INVISIBLE (-6252 4425);
FORCEADD TAP..1
(-6250 4475);
FORCEPROP 3 LASTPIN (-6300 4475) SIG_NAME M_B_CPU0_SA_DQ<10>
J 0
(-6290 4485);
DISPLAY 0.659574 (-6290 4485);
PAINT MONO (-6290 4485);
DISPLAY INVISIBLE (-6290 4485);
FORCEPROP 1 LASTPIN (-6300 4475) BN 10
J 0
(-6312 4483);
DISPLAY 0.489362 (-6312 4483);
PAINT GREEN (-6312 4483);
FORCEPROP 2 LAST CDS_LIB mstr_standard
J 0
(-6250 4475);
DISPLAY 0.723404 (-6250 4475);
PAINT MONO (-6250 4475);
DISPLAY INVISIBLE (-6250 4475);
FORCEPROP 1 LAST BODY_TYPE PLUMBING
J 0
(-6250 4525);
DISPLAY 0.872340 (-6250 4525);
PAINT GREEN (-6250 4525);
DISPLAY INVISIBLE (-6250 4525);
FORCEPROP 1 LAST HDL_TAP TRUE
J 0
(-5925 4350);
DISPLAY 0.872340 (-5925 4350);
DISPLAY INVISIBLE (-5925 4350);
FORCEPROP 1 LAST PATH I249
J 0
(-6252 4475);
DISPLAY 0.872340 (-6252 4475);
PAINT GREEN (-6252 4475);
DISPLAY INVISIBLE (-6252 4475);
FORCEADD TAP..1
(-6250 4675);
FORCEPROP 3 LASTPIN (-6300 4675) SIG_NAME M_B_CPU0_SA_DQ<14>
J 0
(-6290 4685);
DISPLAY 0.659574 (-6290 4685);
PAINT MONO (-6290 4685);
DISPLAY INVISIBLE (-6290 4685);
FORCEPROP 1 LASTPIN (-6300 4675) BN 14
J 0
(-6312 4683);
DISPLAY 0.489362 (-6312 4683);
PAINT GREEN (-6312 4683);
FORCEPROP 2 LAST CDS_LIB mstr_standard
J 0
(-6250 4675);
DISPLAY 0.723404 (-6250 4675);
PAINT MONO (-6250 4675);
DISPLAY INVISIBLE (-6250 4675);
FORCEPROP 1 LAST BODY_TYPE PLUMBING
J 0
(-6250 4725);
DISPLAY 0.872340 (-6250 4725);
PAINT GREEN (-6250 4725);
DISPLAY INVISIBLE (-6250 4725);
FORCEPROP 1 LAST HDL_TAP TRUE
J 0
(-5925 4550);
DISPLAY 0.872340 (-5925 4550);
DISPLAY INVISIBLE (-5925 4550);
FORCEPROP 1 LAST PATH I250
J 0
(-6252 4675);
DISPLAY 0.872340 (-6252 4675);
PAINT GREEN (-6252 4675);
DISPLAY INVISIBLE (-6252 4675);
FORCEADD TAP..1
(-6250 4725);
FORCEPROP 3 LASTPIN (-6300 4725) SIG_NAME M_B_CPU0_SA_DQ<15>
J 0
(-6290 4735);
DISPLAY 0.659574 (-6290 4735);
PAINT MONO (-6290 4735);
DISPLAY INVISIBLE (-6290 4735);
FORCEPROP 1 LASTPIN (-6300 4725) BN 15
J 0
(-6312 4733);
DISPLAY 0.489362 (-6312 4733);
PAINT GREEN (-6312 4733);
FORCEPROP 2 LAST CDS_LIB mstr_standard
J 0
(-6250 4725);
DISPLAY 0.723404 (-6250 4725);
PAINT MONO (-6250 4725);
DISPLAY INVISIBLE (-6250 4725);
FORCEPROP 1 LAST BODY_TYPE PLUMBING
J 0
(-6250 4775);
DISPLAY 0.872340 (-6250 4775);
PAINT GREEN (-6250 4775);
DISPLAY INVISIBLE (-6250 4775);
FORCEPROP 1 LAST HDL_TAP TRUE
J 0
(-5925 4600);
DISPLAY 0.872340 (-5925 4600);
DISPLAY INVISIBLE (-5925 4600);
FORCEPROP 1 LAST PATH I251
J 0
(-6252 4725);
DISPLAY 0.872340 (-6252 4725);
PAINT GREEN (-6252 4725);
DISPLAY INVISIBLE (-6252 4725);
FORCEADD TAP..1
(-6250 4625);
FORCEPROP 3 LASTPIN (-6300 4625) SIG_NAME M_B_CPU0_SA_DQ<13>
J 0
(-6290 4635);
DISPLAY 0.659574 (-6290 4635);
PAINT MONO (-6290 4635);
DISPLAY INVISIBLE (-6290 4635);
FORCEPROP 1 LASTPIN (-6300 4625) BN 13
J 0
(-6312 4633);
DISPLAY 0.489362 (-6312 4633);
PAINT GREEN (-6312 4633);
FORCEPROP 2 LAST CDS_LIB mstr_standard
J 0
(-6250 4625);
DISPLAY 0.723404 (-6250 4625);
PAINT MONO (-6250 4625);
DISPLAY INVISIBLE (-6250 4625);
FORCEPROP 1 LAST BODY_TYPE PLUMBING
J 0
(-6250 4675);
DISPLAY 0.872340 (-6250 4675);
PAINT GREEN (-6250 4675);
DISPLAY INVISIBLE (-6250 4675);
FORCEPROP 1 LAST HDL_TAP TRUE
J 0
(-5925 4500);
DISPLAY 0.872340 (-5925 4500);
DISPLAY INVISIBLE (-5925 4500);
FORCEPROP 1 LAST PATH I252
J 0
(-6252 4625);
DISPLAY 0.872340 (-6252 4625);
PAINT GREEN (-6252 4625);
DISPLAY INVISIBLE (-6252 4625);
FORCEADD TAP..1
(-6250 4575);
FORCEPROP 3 LASTPIN (-6300 4575) SIG_NAME M_B_CPU0_SA_DQ<12>
J 0
(-6290 4585);
DISPLAY 0.659574 (-6290 4585);
PAINT MONO (-6290 4585);
DISPLAY INVISIBLE (-6290 4585);
FORCEPROP 1 LASTPIN (-6300 4575) BN 12
J 0
(-6312 4583);
DISPLAY 0.489362 (-6312 4583);
PAINT GREEN (-6312 4583);
FORCEPROP 2 LAST CDS_LIB mstr_standard
J 0
(-6250 4575);
DISPLAY 0.723404 (-6250 4575);
PAINT MONO (-6250 4575);
DISPLAY INVISIBLE (-6250 4575);
FORCEPROP 1 LAST BODY_TYPE PLUMBING
J 0
(-6250 4625);
DISPLAY 0.872340 (-6250 4625);
PAINT GREEN (-6250 4625);
DISPLAY INVISIBLE (-6250 4625);
FORCEPROP 1 LAST HDL_TAP TRUE
J 0
(-5925 4450);
DISPLAY 0.872340 (-5925 4450);
DISPLAY INVISIBLE (-5925 4450);
FORCEPROP 1 LAST PATH I253
J 0
(-6252 4575);
DISPLAY 0.872340 (-6252 4575);
PAINT GREEN (-6252 4575);
DISPLAY INVISIBLE (-6252 4575);
FORCEADD TAP..1
(-6250 4525);
FORCEPROP 3 LASTPIN (-6300 4525) SIG_NAME M_B_CPU0_SA_DQ<11>
J 0
(-6290 4535);
DISPLAY 0.659574 (-6290 4535);
PAINT MONO (-6290 4535);
DISPLAY INVISIBLE (-6290 4535);
FORCEPROP 1 LASTPIN (-6300 4525) BN 11
J 0
(-6312 4533);
DISPLAY 0.489362 (-6312 4533);
PAINT GREEN (-6312 4533);
FORCEPROP 2 LAST CDS_LIB mstr_standard
J 0
(-6250 4525);
DISPLAY 0.723404 (-6250 4525);
PAINT MONO (-6250 4525);
DISPLAY INVISIBLE (-6250 4525);
FORCEPROP 1 LAST BODY_TYPE PLUMBING
J 0
(-6250 4575);
DISPLAY 0.872340 (-6250 4575);
PAINT GREEN (-6250 4575);
DISPLAY INVISIBLE (-6250 4575);
FORCEPROP 1 LAST HDL_TAP TRUE
J 0
(-5925 4400);
DISPLAY 0.872340 (-5925 4400);
DISPLAY INVISIBLE (-5925 4400);
FORCEPROP 1 LAST PATH I254
J 0
(-6252 4525);
DISPLAY 0.872340 (-6252 4525);
PAINT GREEN (-6252 4525);
DISPLAY INVISIBLE (-6252 4525);
FORCEADD TAP..1
(-6250 4825);
FORCEPROP 3 LASTPIN (-6300 4825) SIG_NAME M_B_CPU0_SA_DQ<17>
J 0
(-6290 4835);
DISPLAY 0.659574 (-6290 4835);
PAINT MONO (-6290 4835);
DISPLAY INVISIBLE (-6290 4835);
FORCEPROP 1 LASTPIN (-6300 4825) BN 17
J 0
(-6312 4833);
DISPLAY 0.489362 (-6312 4833);
PAINT GREEN (-6312 4833);
FORCEPROP 2 LAST CDS_LIB mstr_standard
J 0
(-6250 4825);
DISPLAY 0.723404 (-6250 4825);
PAINT MONO (-6250 4825);
DISPLAY INVISIBLE (-6250 4825);
FORCEPROP 1 LAST BODY_TYPE PLUMBING
J 0
(-6250 4875);
DISPLAY 0.872340 (-6250 4875);
PAINT GREEN (-6250 4875);
DISPLAY INVISIBLE (-6250 4875);
FORCEPROP 1 LAST HDL_TAP TRUE
J 0
(-5925 4700);
DISPLAY 0.872340 (-5925 4700);
DISPLAY INVISIBLE (-5925 4700);
FORCEPROP 1 LAST PATH I255
J 0
(-6252 4825);
DISPLAY 0.872340 (-6252 4825);
PAINT GREEN (-6252 4825);
DISPLAY INVISIBLE (-6252 4825);
FORCEADD TAP..1
(-6250 4875);
FORCEPROP 3 LASTPIN (-6300 4875) SIG_NAME M_B_CPU0_SA_DQ<18>
J 0
(-6290 4885);
DISPLAY 0.659574 (-6290 4885);
PAINT MONO (-6290 4885);
DISPLAY INVISIBLE (-6290 4885);
FORCEPROP 1 LASTPIN (-6300 4875) BN 18
J 0
(-6312 4883);
DISPLAY 0.489362 (-6312 4883);
PAINT GREEN (-6312 4883);
FORCEPROP 2 LAST CDS_LIB mstr_standard
J 0
(-6250 4875);
DISPLAY 0.723404 (-6250 4875);
PAINT MONO (-6250 4875);
DISPLAY INVISIBLE (-6250 4875);
FORCEPROP 1 LAST BODY_TYPE PLUMBING
J 0
(-6250 4925);
DISPLAY 0.872340 (-6250 4925);
PAINT GREEN (-6250 4925);
DISPLAY INVISIBLE (-6250 4925);
FORCEPROP 1 LAST HDL_TAP TRUE
J 0
(-5925 4750);
DISPLAY 0.872340 (-5925 4750);
DISPLAY INVISIBLE (-5925 4750);
FORCEPROP 1 LAST PATH I256
J 0
(-6252 4875);
DISPLAY 0.872340 (-6252 4875);
PAINT GREEN (-6252 4875);
DISPLAY INVISIBLE (-6252 4875);
FORCEADD TAP..1
(-6250 4775);
FORCEPROP 3 LASTPIN (-6300 4775) SIG_NAME M_B_CPU0_SA_DQ<16>
J 0
(-6290 4785);
DISPLAY 0.659574 (-6290 4785);
PAINT MONO (-6290 4785);
DISPLAY INVISIBLE (-6290 4785);
FORCEPROP 1 LASTPIN (-6300 4775) BN 16
J 0
(-6312 4783);
DISPLAY 0.489362 (-6312 4783);
PAINT GREEN (-6312 4783);
FORCEPROP 2 LAST CDS_LIB mstr_standard
J 0
(-6250 4775);
DISPLAY 0.723404 (-6250 4775);
PAINT MONO (-6250 4775);
DISPLAY INVISIBLE (-6250 4775);
FORCEPROP 1 LAST BODY_TYPE PLUMBING
J 0
(-6250 4825);
DISPLAY 0.872340 (-6250 4825);
PAINT GREEN (-6250 4825);
DISPLAY INVISIBLE (-6250 4825);
FORCEPROP 1 LAST HDL_TAP TRUE
J 0
(-5925 4650);
DISPLAY 0.872340 (-5925 4650);
DISPLAY INVISIBLE (-5925 4650);
FORCEPROP 1 LAST PATH I257
J 0
(-6252 4775);
DISPLAY 0.872340 (-6252 4775);
PAINT GREEN (-6252 4775);
DISPLAY INVISIBLE (-6252 4775);
FORCEADD TAP..1
(-6250 4975);
FORCEPROP 3 LASTPIN (-6300 4975) SIG_NAME M_B_CPU0_SA_DQ<20>
J 0
(-6290 4985);
DISPLAY 0.659574 (-6290 4985);
PAINT MONO (-6290 4985);
DISPLAY INVISIBLE (-6290 4985);
FORCEPROP 1 LASTPIN (-6300 4975) BN 20
J 0
(-6312 4983);
DISPLAY 0.489362 (-6312 4983);
PAINT GREEN (-6312 4983);
FORCEPROP 2 LAST CDS_LIB mstr_standard
J 0
(-6250 4975);
DISPLAY 0.723404 (-6250 4975);
PAINT MONO (-6250 4975);
DISPLAY INVISIBLE (-6250 4975);
FORCEPROP 1 LAST BODY_TYPE PLUMBING
J 0
(-6250 5025);
DISPLAY 0.872340 (-6250 5025);
PAINT GREEN (-6250 5025);
DISPLAY INVISIBLE (-6250 5025);
FORCEPROP 1 LAST HDL_TAP TRUE
J 0
(-5925 4850);
DISPLAY 0.872340 (-5925 4850);
DISPLAY INVISIBLE (-5925 4850);
FORCEPROP 1 LAST PATH I258
J 0
(-6252 4975);
DISPLAY 0.872340 (-6252 4975);
PAINT GREEN (-6252 4975);
DISPLAY INVISIBLE (-6252 4975);
FORCEADD TAP..1
(-6250 4925);
FORCEPROP 3 LASTPIN (-6300 4925) SIG_NAME M_B_CPU0_SA_DQ<19>
J 0
(-6290 4935);
DISPLAY 0.659574 (-6290 4935);
PAINT MONO (-6290 4935);
DISPLAY INVISIBLE (-6290 4935);
FORCEPROP 1 LASTPIN (-6300 4925) BN 19
J 0
(-6312 4933);
DISPLAY 0.489362 (-6312 4933);
PAINT GREEN (-6312 4933);
FORCEPROP 2 LAST CDS_LIB mstr_standard
J 0
(-6250 4925);
DISPLAY 0.723404 (-6250 4925);
PAINT MONO (-6250 4925);
DISPLAY INVISIBLE (-6250 4925);
FORCEPROP 1 LAST BODY_TYPE PLUMBING
J 0
(-6250 4975);
DISPLAY 0.872340 (-6250 4975);
PAINT GREEN (-6250 4975);
DISPLAY INVISIBLE (-6250 4975);
FORCEPROP 1 LAST HDL_TAP TRUE
J 0
(-5925 4800);
DISPLAY 0.872340 (-5925 4800);
DISPLAY INVISIBLE (-5925 4800);
FORCEPROP 1 LAST PATH I259
J 0
(-6252 4925);
DISPLAY 0.872340 (-6252 4925);
PAINT GREEN (-6252 4925);
DISPLAY INVISIBLE (-6252 4925);
FORCEADD OFFPAGE..3
(-5500 3925);
FORCEPROP 2 LAST $XR0 11 
J 0
(-5286 3925);
DISPLAY 0.638298 (-5286 3925);
PAINT MONO (-5286 3925);
FORCEPROP 2 LAST CDS_LIB mstr_standard
J 0
(-5500 3925);
DISPLAY 0.723404 (-5500 3925);
PAINT MONO (-5500 3925);
DISPLAY INVISIBLE (-5500 3925);
FORCEPROP 1 LAST OFFPAGE TRUE
J 0
(-5175 3800);
DISPLAY 0.872340 (-5175 3800);
PAINT GREEN (-5175 3800);
DISPLAY INVISIBLE (-5175 3800);
FORCEPROP 1 LAST COMMENT_BODY TRUE
J 0
(-5550 3825);
DISPLAY 0.872340 (-5550 3825);
PAINT GREEN (-5550 3825);
DISPLAY INVISIBLE (-5550 3825);
FORCEPROP 2 LAST PATH I260
J 0
(-5175 3975);
DISPLAY 0.808511 (-5175 3975);
DISPLAY INVISIBLE (-5175 3975);
FORCEADD OFFPAGE..1
(-8550 5175);
FORCEPROP 2 LAST $XR0 11 
J 0
(-8771 5175);
DISPLAY 0.638298 (-8771 5175);
PAINT MONO (-8771 5175);
FORCEPROP 2 LAST CDS_LIB mstr_standard
J 0
(-8550 5175);
DISPLAY 0.723404 (-8550 5175);
PAINT MONO (-8550 5175);
DISPLAY INVISIBLE (-8550 5175);
FORCEPROP 1 LAST OFFPAGE TRUE
J 0
(-8225 5050);
DISPLAY 0.872340 (-8225 5050);
PAINT GREEN (-8225 5050);
DISPLAY INVISIBLE (-8225 5050);
FORCEPROP 1 LAST COMMENT_BODY TRUE
J 0
(-8425 5075);
DISPLAY 0.872340 (-8425 5075);
PAINT GREEN (-8425 5075);
DISPLAY INVISIBLE (-8425 5075);
FORCEPROP 2 LAST PATH I261
J 0
(-8500 5250);
DISPLAY 0.808511 (-8500 5250);
DISPLAY INVISIBLE (-8500 5250);
FORCEADD OFFPAGE..1
(-8550 5575);
FORCEPROP 2 LAST $XR0 11 
J 0
(-8771 5575);
DISPLAY 0.638298 (-8771 5575);
PAINT MONO (-8771 5575);
FORCEPROP 2 LAST CDS_LIB mstr_standard
J 0
(-8550 5575);
DISPLAY 0.723404 (-8550 5575);
PAINT MONO (-8550 5575);
DISPLAY INVISIBLE (-8550 5575);
FORCEPROP 1 LAST OFFPAGE TRUE
J 0
(-8225 5450);
DISPLAY 0.872340 (-8225 5450);
PAINT GREEN (-8225 5450);
DISPLAY INVISIBLE (-8225 5450);
FORCEPROP 1 LAST COMMENT_BODY TRUE
J 0
(-8425 5475);
DISPLAY 0.872340 (-8425 5475);
PAINT GREEN (-8425 5475);
DISPLAY INVISIBLE (-8425 5475);
FORCEPROP 2 LAST PATH I262
J 0
(-8500 5650);
DISPLAY 0.808511 (-8500 5650);
DISPLAY INVISIBLE (-8500 5650);
FORCEADD TAP..1
R 2
(-7950 5125);
FORCEPROP 3 LASTPIN (-7900 5125) SIG_NAME M_B_CPU0_SB_CA<6>
J 0
(-7890 5135);
DISPLAY 0.659574 (-7890 5135);
PAINT MONO (-7890 5135);
DISPLAY INVISIBLE (-7890 5135);
FORCEPROP 1 LASTPIN (-7900 5125) BN 6
J 2
(-7888 5133);
DISPLAY 0.489362 (-7888 5133);
PAINT GREEN (-7888 5133);
FORCEPROP 2 LAST CDS_LIB mstr_standard
J 0
(-7950 5125);
DISPLAY 0.723404 (-7950 5125);
PAINT MONO (-7950 5125);
DISPLAY INVISIBLE (-7950 5125);
FORCEPROP 1 LAST BODY_TYPE PLUMBING
J 2
(-7950 5175);
DISPLAY 0.872340 (-7950 5175);
PAINT GREEN (-7950 5175);
DISPLAY INVISIBLE (-7950 5175);
FORCEPROP 1 LAST HDL_TAP TRUE
J 2
(-8275 5000);
DISPLAY 0.872340 (-8275 5000);
DISPLAY INVISIBLE (-8275 5000);
FORCEPROP 1 LAST PATH I263
J 2
(-7948 5125);
DISPLAY 0.872340 (-7948 5125);
PAINT GREEN (-7948 5125);
DISPLAY INVISIBLE (-7948 5125);
FORCEADD TAP..1
R 2
(-7950 5025);
FORCEPROP 3 LASTPIN (-7900 5025) SIG_NAME M_B_CPU0_SB_CA<4>
J 0
(-7890 5035);
DISPLAY 0.659574 (-7890 5035);
PAINT MONO (-7890 5035);
DISPLAY INVISIBLE (-7890 5035);
FORCEPROP 1 LASTPIN (-7900 5025) BN 4
J 2
(-7888 5033);
DISPLAY 0.489362 (-7888 5033);
PAINT GREEN (-7888 5033);
FORCEPROP 2 LAST CDS_LIB mstr_standard
J 0
(-7950 5025);
DISPLAY 0.723404 (-7950 5025);
PAINT MONO (-7950 5025);
DISPLAY INVISIBLE (-7950 5025);
FORCEPROP 1 LAST BODY_TYPE PLUMBING
J 2
(-7950 5075);
DISPLAY 0.872340 (-7950 5075);
PAINT GREEN (-7950 5075);
DISPLAY INVISIBLE (-7950 5075);
FORCEPROP 1 LAST HDL_TAP TRUE
J 2
(-8275 4900);
DISPLAY 0.872340 (-8275 4900);
DISPLAY INVISIBLE (-8275 4900);
FORCEPROP 1 LAST PATH I264
J 2
(-7948 5025);
DISPLAY 0.872340 (-7948 5025);
PAINT GREEN (-7948 5025);
DISPLAY INVISIBLE (-7948 5025);
FORCEADD TAP..1
R 2
(-7950 5075);
FORCEPROP 3 LASTPIN (-7900 5075) SIG_NAME M_B_CPU0_SB_CA<5>
J 0
(-7890 5085);
DISPLAY 0.659574 (-7890 5085);
PAINT MONO (-7890 5085);
DISPLAY INVISIBLE (-7890 5085);
FORCEPROP 1 LASTPIN (-7900 5075) BN 5
J 2
(-7888 5083);
DISPLAY 0.489362 (-7888 5083);
PAINT GREEN (-7888 5083);
FORCEPROP 2 LAST CDS_LIB mstr_standard
J 0
(-7950 5075);
DISPLAY 0.723404 (-7950 5075);
PAINT MONO (-7950 5075);
DISPLAY INVISIBLE (-7950 5075);
FORCEPROP 1 LAST BODY_TYPE PLUMBING
J 2
(-7950 5125);
DISPLAY 0.872340 (-7950 5125);
PAINT GREEN (-7950 5125);
DISPLAY INVISIBLE (-7950 5125);
FORCEPROP 1 LAST HDL_TAP TRUE
J 2
(-8275 4950);
DISPLAY 0.872340 (-8275 4950);
DISPLAY INVISIBLE (-8275 4950);
FORCEPROP 1 LAST PATH I265
J 2
(-7948 5075);
DISPLAY 0.872340 (-7948 5075);
PAINT GREEN (-7948 5075);
DISPLAY INVISIBLE (-7948 5075);
FORCEADD TAP..1
R 2
(-7950 5225);
FORCEPROP 3 LASTPIN (-7900 5225) SIG_NAME M_B_CPU0_SA_CA<0>
J 0
(-7890 5235);
DISPLAY 0.659574 (-7890 5235);
PAINT MONO (-7890 5235);
DISPLAY INVISIBLE (-7890 5235);
FORCEPROP 1 LASTPIN (-7900 5225) BN 0
J 2
(-7888 5233);
DISPLAY 0.489362 (-7888 5233);
PAINT GREEN (-7888 5233);
FORCEPROP 2 LAST CDS_LIB mstr_standard
J 0
(-7950 5225);
DISPLAY 0.723404 (-7950 5225);
PAINT MONO (-7950 5225);
DISPLAY INVISIBLE (-7950 5225);
FORCEPROP 1 LAST BODY_TYPE PLUMBING
J 2
(-7950 5275);
DISPLAY 0.872340 (-7950 5275);
PAINT GREEN (-7950 5275);
DISPLAY INVISIBLE (-7950 5275);
FORCEPROP 1 LAST HDL_TAP TRUE
J 2
(-8275 5100);
DISPLAY 0.872340 (-8275 5100);
DISPLAY INVISIBLE (-8275 5100);
FORCEPROP 1 LAST PATH I266
J 2
(-7948 5225);
DISPLAY 0.872340 (-7948 5225);
PAINT GREEN (-7948 5225);
DISPLAY INVISIBLE (-7948 5225);
FORCEADD TAP..1
R 2
(-7950 5275);
FORCEPROP 3 LASTPIN (-7900 5275) SIG_NAME M_B_CPU0_SA_CA<1>
J 0
(-7890 5285);
DISPLAY 0.659574 (-7890 5285);
PAINT MONO (-7890 5285);
DISPLAY INVISIBLE (-7890 5285);
FORCEPROP 1 LASTPIN (-7900 5275) BN 1
J 2
(-7888 5283);
DISPLAY 0.489362 (-7888 5283);
PAINT GREEN (-7888 5283);
FORCEPROP 2 LAST CDS_LIB mstr_standard
J 0
(-7950 5275);
DISPLAY 0.723404 (-7950 5275);
PAINT MONO (-7950 5275);
DISPLAY INVISIBLE (-7950 5275);
FORCEPROP 1 LAST BODY_TYPE PLUMBING
J 2
(-7950 5325);
DISPLAY 0.872340 (-7950 5325);
PAINT GREEN (-7950 5325);
DISPLAY INVISIBLE (-7950 5325);
FORCEPROP 1 LAST HDL_TAP TRUE
J 2
(-8275 5150);
DISPLAY 0.872340 (-8275 5150);
DISPLAY INVISIBLE (-8275 5150);
FORCEPROP 1 LAST PATH I267
J 2
(-7948 5275);
DISPLAY 0.872340 (-7948 5275);
PAINT GREEN (-7948 5275);
DISPLAY INVISIBLE (-7948 5275);
FORCEADD TAP..1
R 2
(-7950 5325);
FORCEPROP 3 LASTPIN (-7900 5325) SIG_NAME M_B_CPU0_SA_CA<2>
J 0
(-7890 5335);
DISPLAY 0.659574 (-7890 5335);
PAINT MONO (-7890 5335);
DISPLAY INVISIBLE (-7890 5335);
FORCEPROP 1 LASTPIN (-7900 5325) BN 2
J 2
(-7888 5333);
DISPLAY 0.489362 (-7888 5333);
PAINT GREEN (-7888 5333);
FORCEPROP 2 LAST CDS_LIB mstr_standard
J 0
(-7950 5325);
DISPLAY 0.723404 (-7950 5325);
PAINT MONO (-7950 5325);
DISPLAY INVISIBLE (-7950 5325);
FORCEPROP 1 LAST BODY_TYPE PLUMBING
J 2
(-7950 5375);
DISPLAY 0.872340 (-7950 5375);
PAINT GREEN (-7950 5375);
DISPLAY INVISIBLE (-7950 5375);
FORCEPROP 1 LAST HDL_TAP TRUE
J 2
(-8275 5200);
DISPLAY 0.872340 (-8275 5200);
DISPLAY INVISIBLE (-8275 5200);
FORCEPROP 1 LAST PATH I268
J 2
(-7948 5325);
DISPLAY 0.872340 (-7948 5325);
PAINT GREEN (-7948 5325);
DISPLAY INVISIBLE (-7948 5325);
FORCEADD TAP..1
R 2
(-7950 5375);
FORCEPROP 3 LASTPIN (-7900 5375) SIG_NAME M_B_CPU0_SA_CA<3>
J 0
(-7890 5385);
DISPLAY 0.659574 (-7890 5385);
PAINT MONO (-7890 5385);
DISPLAY INVISIBLE (-7890 5385);
FORCEPROP 1 LASTPIN (-7900 5375) BN 3
J 2
(-7888 5383);
DISPLAY 0.489362 (-7888 5383);
PAINT GREEN (-7888 5383);
FORCEPROP 2 LAST CDS_LIB mstr_standard
J 0
(-7950 5375);
DISPLAY 0.723404 (-7950 5375);
PAINT MONO (-7950 5375);
DISPLAY INVISIBLE (-7950 5375);
FORCEPROP 1 LAST BODY_TYPE PLUMBING
J 2
(-7950 5425);
DISPLAY 0.872340 (-7950 5425);
PAINT GREEN (-7950 5425);
DISPLAY INVISIBLE (-7950 5425);
FORCEPROP 1 LAST HDL_TAP TRUE
J 2
(-8275 5250);
DISPLAY 0.872340 (-8275 5250);
DISPLAY INVISIBLE (-8275 5250);
FORCEPROP 1 LAST PATH I269
J 2
(-7948 5375);
DISPLAY 0.872340 (-7948 5375);
PAINT GREEN (-7948 5375);
DISPLAY INVISIBLE (-7948 5375);
FORCEADD TAP..1
R 2
(-7950 5475);
FORCEPROP 3 LASTPIN (-7900 5475) SIG_NAME M_B_CPU0_SA_CA<5>
J 0
(-7890 5485);
DISPLAY 0.659574 (-7890 5485);
PAINT MONO (-7890 5485);
DISPLAY INVISIBLE (-7890 5485);
FORCEPROP 1 LASTPIN (-7900 5475) BN 5
J 2
(-7888 5483);
DISPLAY 0.489362 (-7888 5483);
PAINT GREEN (-7888 5483);
FORCEPROP 2 LAST CDS_LIB mstr_standard
J 0
(-7950 5475);
DISPLAY 0.723404 (-7950 5475);
PAINT MONO (-7950 5475);
DISPLAY INVISIBLE (-7950 5475);
FORCEPROP 1 LAST BODY_TYPE PLUMBING
J 2
(-7950 5525);
DISPLAY 0.872340 (-7950 5525);
PAINT GREEN (-7950 5525);
DISPLAY INVISIBLE (-7950 5525);
FORCEPROP 1 LAST HDL_TAP TRUE
J 2
(-8275 5350);
DISPLAY 0.872340 (-8275 5350);
DISPLAY INVISIBLE (-8275 5350);
FORCEPROP 1 LAST PATH I270
J 2
(-7948 5475);
DISPLAY 0.872340 (-7948 5475);
PAINT GREEN (-7948 5475);
DISPLAY INVISIBLE (-7948 5475);
FORCEADD TAP..1
R 2
(-7950 5425);
FORCEPROP 3 LASTPIN (-7900 5425) SIG_NAME M_B_CPU0_SA_CA<4>
J 0
(-7890 5435);
DISPLAY 0.659574 (-7890 5435);
PAINT MONO (-7890 5435);
DISPLAY INVISIBLE (-7890 5435);
FORCEPROP 1 LASTPIN (-7900 5425) BN 4
J 2
(-7888 5433);
DISPLAY 0.489362 (-7888 5433);
PAINT GREEN (-7888 5433);
FORCEPROP 2 LAST CDS_LIB mstr_standard
J 0
(-7950 5425);
DISPLAY 0.723404 (-7950 5425);
PAINT MONO (-7950 5425);
DISPLAY INVISIBLE (-7950 5425);
FORCEPROP 1 LAST BODY_TYPE PLUMBING
J 2
(-7950 5475);
DISPLAY 0.872340 (-7950 5475);
PAINT GREEN (-7950 5475);
DISPLAY INVISIBLE (-7950 5475);
FORCEPROP 1 LAST HDL_TAP TRUE
J 2
(-8275 5300);
DISPLAY 0.872340 (-8275 5300);
DISPLAY INVISIBLE (-8275 5300);
FORCEPROP 1 LAST PATH I271
J 2
(-7948 5425);
DISPLAY 0.872340 (-7948 5425);
PAINT GREEN (-7948 5425);
DISPLAY INVISIBLE (-7948 5425);
FORCEADD TAP..1
R 2
(-7950 5525);
FORCEPROP 3 LASTPIN (-7900 5525) SIG_NAME M_B_CPU0_SA_CA<6>
J 0
(-7890 5535);
DISPLAY 0.659574 (-7890 5535);
PAINT MONO (-7890 5535);
DISPLAY INVISIBLE (-7890 5535);
FORCEPROP 1 LASTPIN (-7900 5525) BN 6
J 2
(-7888 5533);
DISPLAY 0.489362 (-7888 5533);
PAINT GREEN (-7888 5533);
FORCEPROP 2 LAST CDS_LIB mstr_standard
J 0
(-7950 5525);
DISPLAY 0.723404 (-7950 5525);
PAINT MONO (-7950 5525);
DISPLAY INVISIBLE (-7950 5525);
FORCEPROP 1 LAST BODY_TYPE PLUMBING
J 2
(-7950 5575);
DISPLAY 0.872340 (-7950 5575);
PAINT GREEN (-7950 5575);
DISPLAY INVISIBLE (-7950 5575);
FORCEPROP 1 LAST HDL_TAP TRUE
J 2
(-8275 5400);
DISPLAY 0.872340 (-8275 5400);
DISPLAY INVISIBLE (-8275 5400);
FORCEPROP 1 LAST PATH I272
J 2
(-7948 5525);
DISPLAY 0.872340 (-7948 5525);
PAINT GREEN (-7948 5525);
DISPLAY INVISIBLE (-7948 5525);
FORCEADD TAP..1
(-6250 5125);
FORCEPROP 3 LASTPIN (-6300 5125) SIG_NAME M_B_CPU0_SA_DQ<23>
J 0
(-6290 5135);
DISPLAY 0.659574 (-6290 5135);
PAINT MONO (-6290 5135);
DISPLAY INVISIBLE (-6290 5135);
FORCEPROP 1 LASTPIN (-6300 5125) BN 23
J 0
(-6312 5133);
DISPLAY 0.489362 (-6312 5133);
PAINT GREEN (-6312 5133);
FORCEPROP 2 LAST CDS_LIB mstr_standard
J 0
(-6250 5125);
DISPLAY 0.723404 (-6250 5125);
PAINT MONO (-6250 5125);
DISPLAY INVISIBLE (-6250 5125);
FORCEPROP 1 LAST BODY_TYPE PLUMBING
J 0
(-6250 5175);
DISPLAY 0.872340 (-6250 5175);
PAINT GREEN (-6250 5175);
DISPLAY INVISIBLE (-6250 5175);
FORCEPROP 1 LAST HDL_TAP TRUE
J 0
(-5925 5000);
DISPLAY 0.872340 (-5925 5000);
DISPLAY INVISIBLE (-5925 5000);
FORCEPROP 1 LAST PATH I273
J 0
(-6252 5125);
DISPLAY 0.872340 (-6252 5125);
PAINT GREEN (-6252 5125);
DISPLAY INVISIBLE (-6252 5125);
FORCEADD TAP..1
(-6250 5025);
FORCEPROP 3 LASTPIN (-6300 5025) SIG_NAME M_B_CPU0_SA_DQ<21>
J 0
(-6290 5035);
DISPLAY 0.659574 (-6290 5035);
PAINT MONO (-6290 5035);
DISPLAY INVISIBLE (-6290 5035);
FORCEPROP 1 LASTPIN (-6300 5025) BN 21
J 0
(-6312 5033);
DISPLAY 0.489362 (-6312 5033);
PAINT GREEN (-6312 5033);
FORCEPROP 2 LAST CDS_LIB mstr_standard
J 0
(-6250 5025);
DISPLAY 0.723404 (-6250 5025);
PAINT MONO (-6250 5025);
DISPLAY INVISIBLE (-6250 5025);
FORCEPROP 1 LAST BODY_TYPE PLUMBING
J 0
(-6250 5075);
DISPLAY 0.872340 (-6250 5075);
PAINT GREEN (-6250 5075);
DISPLAY INVISIBLE (-6250 5075);
FORCEPROP 1 LAST HDL_TAP TRUE
J 0
(-5925 4900);
DISPLAY 0.872340 (-5925 4900);
DISPLAY INVISIBLE (-5925 4900);
FORCEPROP 1 LAST PATH I274
J 0
(-6252 5025);
DISPLAY 0.872340 (-6252 5025);
PAINT GREEN (-6252 5025);
DISPLAY INVISIBLE (-6252 5025);
FORCEADD TAP..1
(-6250 5075);
FORCEPROP 3 LASTPIN (-6300 5075) SIG_NAME M_B_CPU0_SA_DQ<22>
J 0
(-6290 5085);
DISPLAY 0.659574 (-6290 5085);
PAINT MONO (-6290 5085);
DISPLAY INVISIBLE (-6290 5085);
FORCEPROP 1 LASTPIN (-6300 5075) BN 22
J 0
(-6312 5083);
DISPLAY 0.489362 (-6312 5083);
PAINT GREEN (-6312 5083);
FORCEPROP 2 LAST CDS_LIB mstr_standard
J 0
(-6250 5075);
DISPLAY 0.723404 (-6250 5075);
PAINT MONO (-6250 5075);
DISPLAY INVISIBLE (-6250 5075);
FORCEPROP 1 LAST BODY_TYPE PLUMBING
J 0
(-6250 5125);
DISPLAY 0.872340 (-6250 5125);
PAINT GREEN (-6250 5125);
DISPLAY INVISIBLE (-6250 5125);
FORCEPROP 1 LAST HDL_TAP TRUE
J 0
(-5925 4950);
DISPLAY 0.872340 (-5925 4950);
DISPLAY INVISIBLE (-5925 4950);
FORCEPROP 1 LAST PATH I275
J 0
(-6252 5075);
DISPLAY 0.872340 (-6252 5075);
PAINT GREEN (-6252 5075);
DISPLAY INVISIBLE (-6252 5075);
FORCEADD TAP..1
(-6250 5175);
FORCEPROP 3 LASTPIN (-6300 5175) SIG_NAME M_B_CPU0_SA_DQ<24>
J 0
(-6290 5185);
DISPLAY 0.659574 (-6290 5185);
PAINT MONO (-6290 5185);
DISPLAY INVISIBLE (-6290 5185);
FORCEPROP 1 LASTPIN (-6300 5175) BN 24
J 0
(-6312 5183);
DISPLAY 0.489362 (-6312 5183);
PAINT GREEN (-6312 5183);
FORCEPROP 2 LAST CDS_LIB mstr_standard
J 0
(-6250 5175);
DISPLAY 0.723404 (-6250 5175);
PAINT MONO (-6250 5175);
DISPLAY INVISIBLE (-6250 5175);
FORCEPROP 1 LAST BODY_TYPE PLUMBING
J 0
(-6250 5225);
DISPLAY 0.872340 (-6250 5225);
PAINT GREEN (-6250 5225);
DISPLAY INVISIBLE (-6250 5225);
FORCEPROP 1 LAST HDL_TAP TRUE
J 0
(-5925 5050);
DISPLAY 0.872340 (-5925 5050);
DISPLAY INVISIBLE (-5925 5050);
FORCEPROP 1 LAST PATH I276
J 0
(-6252 5175);
DISPLAY 0.872340 (-6252 5175);
PAINT GREEN (-6252 5175);
DISPLAY INVISIBLE (-6252 5175);
FORCEADD TAP..1
(-6250 5225);
FORCEPROP 3 LASTPIN (-6300 5225) SIG_NAME M_B_CPU0_SA_DQ<25>
J 0
(-6290 5235);
DISPLAY 0.659574 (-6290 5235);
PAINT MONO (-6290 5235);
DISPLAY INVISIBLE (-6290 5235);
FORCEPROP 1 LASTPIN (-6300 5225) BN 25
J 0
(-6312 5233);
DISPLAY 0.489362 (-6312 5233);
PAINT GREEN (-6312 5233);
FORCEPROP 2 LAST CDS_LIB mstr_standard
J 0
(-6250 5225);
DISPLAY 0.723404 (-6250 5225);
PAINT MONO (-6250 5225);
DISPLAY INVISIBLE (-6250 5225);
FORCEPROP 1 LAST BODY_TYPE PLUMBING
J 0
(-6250 5275);
DISPLAY 0.872340 (-6250 5275);
PAINT GREEN (-6250 5275);
DISPLAY INVISIBLE (-6250 5275);
FORCEPROP 1 LAST HDL_TAP TRUE
J 0
(-5925 5100);
DISPLAY 0.872340 (-5925 5100);
DISPLAY INVISIBLE (-5925 5100);
FORCEPROP 1 LAST PATH I277
J 0
(-6252 5225);
DISPLAY 0.872340 (-6252 5225);
PAINT GREEN (-6252 5225);
DISPLAY INVISIBLE (-6252 5225);
FORCEADD TAP..1
(-6250 5275);
FORCEPROP 3 LASTPIN (-6300 5275) SIG_NAME M_B_CPU0_SA_DQ<26>
J 0
(-6290 5285);
DISPLAY 0.659574 (-6290 5285);
PAINT MONO (-6290 5285);
DISPLAY INVISIBLE (-6290 5285);
FORCEPROP 1 LASTPIN (-6300 5275) BN 26
J 0
(-6312 5283);
DISPLAY 0.489362 (-6312 5283);
PAINT GREEN (-6312 5283);
FORCEPROP 2 LAST CDS_LIB mstr_standard
J 0
(-6250 5275);
DISPLAY 0.723404 (-6250 5275);
PAINT MONO (-6250 5275);
DISPLAY INVISIBLE (-6250 5275);
FORCEPROP 1 LAST BODY_TYPE PLUMBING
J 0
(-6250 5325);
DISPLAY 0.872340 (-6250 5325);
PAINT GREEN (-6250 5325);
DISPLAY INVISIBLE (-6250 5325);
FORCEPROP 1 LAST HDL_TAP TRUE
J 0
(-5925 5150);
DISPLAY 0.872340 (-5925 5150);
DISPLAY INVISIBLE (-5925 5150);
FORCEPROP 1 LAST PATH I278
J 0
(-6252 5275);
DISPLAY 0.872340 (-6252 5275);
PAINT GREEN (-6252 5275);
DISPLAY INVISIBLE (-6252 5275);
FORCEADD TAP..1
(-6250 5525);
FORCEPROP 3 LASTPIN (-6300 5525) SIG_NAME M_B_CPU0_SA_DQ<31>
J 0
(-6290 5535);
DISPLAY 0.659574 (-6290 5535);
PAINT MONO (-6290 5535);
DISPLAY INVISIBLE (-6290 5535);
FORCEPROP 1 LASTPIN (-6300 5525) BN 31
J 0
(-6312 5533);
DISPLAY 0.489362 (-6312 5533);
PAINT GREEN (-6312 5533);
FORCEPROP 2 LAST CDS_LIB mstr_standard
J 0
(-6250 5525);
DISPLAY 0.723404 (-6250 5525);
PAINT MONO (-6250 5525);
DISPLAY INVISIBLE (-6250 5525);
FORCEPROP 1 LAST BODY_TYPE PLUMBING
J 0
(-6250 5575);
DISPLAY 0.872340 (-6250 5575);
PAINT GREEN (-6250 5575);
DISPLAY INVISIBLE (-6250 5575);
FORCEPROP 1 LAST HDL_TAP TRUE
J 0
(-5925 5400);
DISPLAY 0.872340 (-5925 5400);
DISPLAY INVISIBLE (-5925 5400);
FORCEPROP 1 LAST PATH I279
J 0
(-6252 5525);
DISPLAY 0.872340 (-6252 5525);
PAINT GREEN (-6252 5525);
DISPLAY INVISIBLE (-6252 5525);
FORCEADD TAP..1
(-6250 5325);
FORCEPROP 3 LASTPIN (-6300 5325) SIG_NAME M_B_CPU0_SA_DQ<27>
J 0
(-6290 5335);
DISPLAY 0.659574 (-6290 5335);
PAINT MONO (-6290 5335);
DISPLAY INVISIBLE (-6290 5335);
FORCEPROP 1 LASTPIN (-6300 5325) BN 27
J 0
(-6312 5333);
DISPLAY 0.489362 (-6312 5333);
PAINT GREEN (-6312 5333);
FORCEPROP 2 LAST CDS_LIB mstr_standard
J 0
(-6250 5325);
DISPLAY 0.723404 (-6250 5325);
PAINT MONO (-6250 5325);
DISPLAY INVISIBLE (-6250 5325);
FORCEPROP 1 LAST BODY_TYPE PLUMBING
J 0
(-6250 5375);
DISPLAY 0.872340 (-6250 5375);
PAINT GREEN (-6250 5375);
DISPLAY INVISIBLE (-6250 5375);
FORCEPROP 1 LAST HDL_TAP TRUE
J 0
(-5925 5200);
DISPLAY 0.872340 (-5925 5200);
DISPLAY INVISIBLE (-5925 5200);
FORCEPROP 1 LAST PATH I280
J 0
(-6252 5325);
DISPLAY 0.872340 (-6252 5325);
PAINT GREEN (-6252 5325);
DISPLAY INVISIBLE (-6252 5325);
FORCEADD TAP..1
(-6250 5375);
FORCEPROP 3 LASTPIN (-6300 5375) SIG_NAME M_B_CPU0_SA_DQ<28>
J 0
(-6290 5385);
DISPLAY 0.659574 (-6290 5385);
PAINT MONO (-6290 5385);
DISPLAY INVISIBLE (-6290 5385);
FORCEPROP 1 LASTPIN (-6300 5375) BN 28
J 0
(-6312 5383);
DISPLAY 0.489362 (-6312 5383);
PAINT GREEN (-6312 5383);
FORCEPROP 2 LAST CDS_LIB mstr_standard
J 0
(-6250 5375);
DISPLAY 0.723404 (-6250 5375);
PAINT MONO (-6250 5375);
DISPLAY INVISIBLE (-6250 5375);
FORCEPROP 1 LAST BODY_TYPE PLUMBING
J 0
(-6250 5425);
DISPLAY 0.872340 (-6250 5425);
PAINT GREEN (-6250 5425);
DISPLAY INVISIBLE (-6250 5425);
FORCEPROP 1 LAST HDL_TAP TRUE
J 0
(-5925 5250);
DISPLAY 0.872340 (-5925 5250);
DISPLAY INVISIBLE (-5925 5250);
FORCEPROP 1 LAST PATH I281
J 0
(-6252 5375);
DISPLAY 0.872340 (-6252 5375);
PAINT GREEN (-6252 5375);
DISPLAY INVISIBLE (-6252 5375);
FORCEADD TAP..1
(-6250 5475);
FORCEPROP 3 LASTPIN (-6300 5475) SIG_NAME M_B_CPU0_SA_DQ<30>
J 0
(-6290 5485);
DISPLAY 0.659574 (-6290 5485);
PAINT MONO (-6290 5485);
DISPLAY INVISIBLE (-6290 5485);
FORCEPROP 1 LASTPIN (-6300 5475) BN 30
J 0
(-6312 5483);
DISPLAY 0.489362 (-6312 5483);
PAINT GREEN (-6312 5483);
FORCEPROP 2 LAST CDS_LIB mstr_standard
J 0
(-6250 5475);
DISPLAY 0.723404 (-6250 5475);
PAINT MONO (-6250 5475);
DISPLAY INVISIBLE (-6250 5475);
FORCEPROP 1 LAST BODY_TYPE PLUMBING
J 0
(-6250 5525);
DISPLAY 0.872340 (-6250 5525);
PAINT GREEN (-6250 5525);
DISPLAY INVISIBLE (-6250 5525);
FORCEPROP 1 LAST HDL_TAP TRUE
J 0
(-5925 5350);
DISPLAY 0.872340 (-5925 5350);
DISPLAY INVISIBLE (-5925 5350);
FORCEPROP 1 LAST PATH I282
J 0
(-6252 5475);
DISPLAY 0.872340 (-6252 5475);
PAINT GREEN (-6252 5475);
DISPLAY INVISIBLE (-6252 5475);
FORCEADD TAP..1
(-6250 5425);
FORCEPROP 3 LASTPIN (-6300 5425) SIG_NAME M_B_CPU0_SA_DQ<29>
J 0
(-6290 5435);
DISPLAY 0.659574 (-6290 5435);
PAINT MONO (-6290 5435);
DISPLAY INVISIBLE (-6290 5435);
FORCEPROP 1 LASTPIN (-6300 5425) BN 29
J 0
(-6312 5433);
DISPLAY 0.489362 (-6312 5433);
PAINT GREEN (-6312 5433);
FORCEPROP 2 LAST CDS_LIB mstr_standard
J 0
(-6250 5425);
DISPLAY 0.723404 (-6250 5425);
PAINT MONO (-6250 5425);
DISPLAY INVISIBLE (-6250 5425);
FORCEPROP 1 LAST BODY_TYPE PLUMBING
J 0
(-6250 5475);
DISPLAY 0.872340 (-6250 5475);
PAINT GREEN (-6250 5475);
DISPLAY INVISIBLE (-6250 5475);
FORCEPROP 1 LAST HDL_TAP TRUE
J 0
(-5925 5300);
DISPLAY 0.872340 (-5925 5300);
DISPLAY INVISIBLE (-5925 5300);
FORCEPROP 1 LAST PATH I283
J 0
(-6252 5425);
DISPLAY 0.872340 (-6252 5425);
PAINT GREEN (-6252 5425);
DISPLAY INVISIBLE (-6252 5425);
FORCEADD OFFPAGE..3
(-5500 5575);
FORCEPROP 2 LAST $XR0 11 
J 0
(-5286 5575);
DISPLAY 0.638298 (-5286 5575);
PAINT MONO (-5286 5575);
FORCEPROP 2 LAST CDS_LIB mstr_standard
J 0
(-5500 5575);
DISPLAY 0.723404 (-5500 5575);
PAINT MONO (-5500 5575);
DISPLAY INVISIBLE (-5500 5575);
FORCEPROP 1 LAST OFFPAGE TRUE
J 0
(-5175 5450);
DISPLAY 0.872340 (-5175 5450);
PAINT GREEN (-5175 5450);
DISPLAY INVISIBLE (-5175 5450);
FORCEPROP 1 LAST COMMENT_BODY TRUE
J 0
(-5550 5475);
DISPLAY 0.872340 (-5550 5475);
PAINT GREEN (-5550 5475);
DISPLAY INVISIBLE (-5550 5475);
FORCEPROP 2 LAST PATH I284
J 0
(-5275 5625);
DISPLAY 0.808511 (-5275 5625);
DISPLAY INVISIBLE (-5275 5625);
FORCEADD TAP..1
(-3650 2700);
FORCEPROP 3 LASTPIN (-3700 2700) SIG_NAME M_B_CPU0_SB_DQS_DP<0>
J 0
(-3690 2710);
DISPLAY 0.659574 (-3690 2710);
PAINT MONO (-3690 2710);
DISPLAY INVISIBLE (-3690 2710);
FORCEPROP 1 LASTPIN (-3700 2700) BN 0
J 0
(-3712 2708);
DISPLAY 0.489362 (-3712 2708);
PAINT GREEN (-3712 2708);
FORCEPROP 2 LAST CDS_LIB mstr_standard
J 0
(-3650 2700);
DISPLAY 0.723404 (-3650 2700);
PAINT MONO (-3650 2700);
DISPLAY INVISIBLE (-3650 2700);
FORCEPROP 1 LAST BODY_TYPE PLUMBING
J 0
(-3650 2750);
DISPLAY 0.872340 (-3650 2750);
PAINT GREEN (-3650 2750);
DISPLAY INVISIBLE (-3650 2750);
FORCEPROP 1 LAST HDL_TAP TRUE
J 0
(-3325 2575);
DISPLAY 0.872340 (-3325 2575);
DISPLAY INVISIBLE (-3325 2575);
FORCEPROP 1 LAST PATH I285
J 0
(-3652 2700);
DISPLAY 0.872340 (-3652 2700);
PAINT GREEN (-3652 2700);
DISPLAY INVISIBLE (-3652 2700);
FORCEADD TAP..1
(-3650 2800);
FORCEPROP 3 LASTPIN (-3700 2800) SIG_NAME M_B_CPU0_SB_DQS_DP<1>
J 0
(-3690 2810);
DISPLAY 0.659574 (-3690 2810);
PAINT MONO (-3690 2810);
DISPLAY INVISIBLE (-3690 2810);
FORCEPROP 1 LASTPIN (-3700 2800) BN 1
J 0
(-3712 2808);
DISPLAY 0.489362 (-3712 2808);
PAINT GREEN (-3712 2808);
FORCEPROP 2 LAST CDS_LIB mstr_standard
J 0
(-3650 2800);
DISPLAY 0.723404 (-3650 2800);
PAINT MONO (-3650 2800);
DISPLAY INVISIBLE (-3650 2800);
FORCEPROP 1 LAST BODY_TYPE PLUMBING
J 0
(-3650 2850);
DISPLAY 0.872340 (-3650 2850);
PAINT GREEN (-3650 2850);
DISPLAY INVISIBLE (-3650 2850);
FORCEPROP 1 LAST HDL_TAP TRUE
J 0
(-3325 2675);
DISPLAY 0.872340 (-3325 2675);
DISPLAY INVISIBLE (-3325 2675);
FORCEPROP 1 LAST PATH I286
J 0
(-3652 2800);
DISPLAY 0.872340 (-3652 2800);
PAINT GREEN (-3652 2800);
DISPLAY INVISIBLE (-3652 2800);
FORCEADD TAP..1
(-3450 2850);
FORCEPROP 3 LASTPIN (-3500 2850) SIG_NAME M_B_CPU0_SB_DQS_DN<2>
J 0
(-3490 2860);
DISPLAY 0.659574 (-3490 2860);
PAINT MONO (-3490 2860);
DISPLAY INVISIBLE (-3490 2860);
FORCEPROP 1 LASTPIN (-3500 2850) BN 2
J 0
(-3512 2858);
DISPLAY 0.489362 (-3512 2858);
PAINT GREEN (-3512 2858);
FORCEPROP 2 LAST CDS_LIB mstr_standard
J 0
(-3450 2850);
DISPLAY 0.723404 (-3450 2850);
PAINT MONO (-3450 2850);
DISPLAY INVISIBLE (-3450 2850);
FORCEPROP 1 LAST BODY_TYPE PLUMBING
J 0
(-3450 2900);
DISPLAY 0.872340 (-3450 2900);
PAINT GREEN (-3450 2900);
DISPLAY INVISIBLE (-3450 2900);
FORCEPROP 1 LAST HDL_TAP TRUE
J 0
(-3125 2725);
DISPLAY 0.872340 (-3125 2725);
DISPLAY INVISIBLE (-3125 2725);
FORCEPROP 1 LAST PATH I287
J 0
(-3452 2850);
DISPLAY 0.872340 (-3452 2850);
PAINT GREEN (-3452 2850);
DISPLAY INVISIBLE (-3452 2850);
FORCEADD TAP..1
(-3450 2750);
FORCEPROP 3 LASTPIN (-3500 2750) SIG_NAME M_B_CPU0_SB_DQS_DN<1>
J 0
(-3490 2760);
DISPLAY 0.659574 (-3490 2760);
PAINT MONO (-3490 2760);
DISPLAY INVISIBLE (-3490 2760);
FORCEPROP 1 LASTPIN (-3500 2750) BN 1
J 0
(-3512 2758);
DISPLAY 0.489362 (-3512 2758);
PAINT GREEN (-3512 2758);
FORCEPROP 2 LAST CDS_LIB mstr_standard
J 0
(-3450 2750);
DISPLAY 0.723404 (-3450 2750);
PAINT MONO (-3450 2750);
DISPLAY INVISIBLE (-3450 2750);
FORCEPROP 1 LAST BODY_TYPE PLUMBING
J 0
(-3450 2800);
DISPLAY 0.872340 (-3450 2800);
PAINT GREEN (-3450 2800);
DISPLAY INVISIBLE (-3450 2800);
FORCEPROP 1 LAST HDL_TAP TRUE
J 0
(-3125 2625);
DISPLAY 0.872340 (-3125 2625);
DISPLAY INVISIBLE (-3125 2625);
FORCEPROP 1 LAST PATH I288
J 0
(-3452 2750);
DISPLAY 0.872340 (-3452 2750);
PAINT GREEN (-3452 2750);
DISPLAY INVISIBLE (-3452 2750);
FORCEADD TAP..1
(-3450 2650);
FORCEPROP 3 LASTPIN (-3500 2650) SIG_NAME M_B_CPU0_SB_DQS_DN<0>
J 0
(-3490 2660);
DISPLAY 0.659574 (-3490 2660);
PAINT MONO (-3490 2660);
DISPLAY INVISIBLE (-3490 2660);
FORCEPROP 1 LASTPIN (-3500 2650) BN 0
J 0
(-3512 2658);
DISPLAY 0.489362 (-3512 2658);
PAINT GREEN (-3512 2658);
FORCEPROP 2 LAST CDS_LIB mstr_standard
J 0
(-3450 2650);
DISPLAY 0.723404 (-3450 2650);
PAINT MONO (-3450 2650);
DISPLAY INVISIBLE (-3450 2650);
FORCEPROP 1 LAST BODY_TYPE PLUMBING
J 0
(-3450 2700);
DISPLAY 0.872340 (-3450 2700);
PAINT GREEN (-3450 2700);
DISPLAY INVISIBLE (-3450 2700);
FORCEPROP 1 LAST HDL_TAP TRUE
J 0
(-3125 2525);
DISPLAY 0.872340 (-3125 2525);
DISPLAY INVISIBLE (-3125 2525);
FORCEPROP 1 LAST PATH I289
J 0
(-3452 2650);
DISPLAY 0.872340 (-3452 2650);
PAINT GREEN (-3452 2650);
DISPLAY INVISIBLE (-3452 2650);
FORCEADD TAP..1
(-3650 2900);
FORCEPROP 3 LASTPIN (-3700 2900) SIG_NAME M_B_CPU0_SB_DQS_DP<2>
J 0
(-3690 2910);
DISPLAY 0.659574 (-3690 2910);
PAINT MONO (-3690 2910);
DISPLAY INVISIBLE (-3690 2910);
FORCEPROP 1 LASTPIN (-3700 2900) BN 2
J 0
(-3712 2908);
DISPLAY 0.489362 (-3712 2908);
PAINT GREEN (-3712 2908);
FORCEPROP 2 LAST CDS_LIB mstr_standard
J 0
(-3650 2900);
DISPLAY 0.723404 (-3650 2900);
PAINT MONO (-3650 2900);
DISPLAY INVISIBLE (-3650 2900);
FORCEPROP 1 LAST BODY_TYPE PLUMBING
J 0
(-3650 2950);
DISPLAY 0.872340 (-3650 2950);
PAINT GREEN (-3650 2950);
DISPLAY INVISIBLE (-3650 2950);
FORCEPROP 1 LAST HDL_TAP TRUE
J 0
(-3325 2775);
DISPLAY 0.872340 (-3325 2775);
DISPLAY INVISIBLE (-3325 2775);
FORCEPROP 1 LAST PATH I290
J 0
(-3652 2900);
DISPLAY 0.872340 (-3652 2900);
PAINT GREEN (-3652 2900);
DISPLAY INVISIBLE (-3652 2900);
FORCEADD TAP..1
(-3650 3000);
FORCEPROP 3 LASTPIN (-3700 3000) SIG_NAME M_B_CPU0_SB_DQS_DP<3>
J 0
(-3690 3010);
DISPLAY 0.659574 (-3690 3010);
PAINT MONO (-3690 3010);
DISPLAY INVISIBLE (-3690 3010);
FORCEPROP 1 LASTPIN (-3700 3000) BN 3
J 0
(-3712 3008);
DISPLAY 0.489362 (-3712 3008);
PAINT GREEN (-3712 3008);
FORCEPROP 2 LAST CDS_LIB mstr_standard
J 0
(-3650 3000);
DISPLAY 0.723404 (-3650 3000);
PAINT MONO (-3650 3000);
DISPLAY INVISIBLE (-3650 3000);
FORCEPROP 1 LAST BODY_TYPE PLUMBING
J 0
(-3650 3050);
DISPLAY 0.872340 (-3650 3050);
PAINT GREEN (-3650 3050);
DISPLAY INVISIBLE (-3650 3050);
FORCEPROP 1 LAST HDL_TAP TRUE
J 0
(-3325 2875);
DISPLAY 0.872340 (-3325 2875);
DISPLAY INVISIBLE (-3325 2875);
FORCEPROP 1 LAST PATH I291
J 0
(-3652 3000);
DISPLAY 0.872340 (-3652 3000);
PAINT GREEN (-3652 3000);
DISPLAY INVISIBLE (-3652 3000);
FORCEADD TAP..1
(-3650 3100);
FORCEPROP 3 LASTPIN (-3700 3100) SIG_NAME M_B_CPU0_SB_DQS_DP<4>
J 0
(-3690 3110);
DISPLAY 0.659574 (-3690 3110);
PAINT MONO (-3690 3110);
DISPLAY INVISIBLE (-3690 3110);
FORCEPROP 1 LASTPIN (-3700 3100) BN 4
J 0
(-3712 3108);
DISPLAY 0.489362 (-3712 3108);
PAINT GREEN (-3712 3108);
FORCEPROP 2 LAST CDS_LIB mstr_standard
J 0
(-3650 3100);
DISPLAY 0.723404 (-3650 3100);
PAINT MONO (-3650 3100);
DISPLAY INVISIBLE (-3650 3100);
FORCEPROP 1 LAST BODY_TYPE PLUMBING
J 0
(-3650 3150);
DISPLAY 0.872340 (-3650 3150);
PAINT GREEN (-3650 3150);
DISPLAY INVISIBLE (-3650 3150);
FORCEPROP 1 LAST HDL_TAP TRUE
J 0
(-3325 2975);
DISPLAY 0.872340 (-3325 2975);
DISPLAY INVISIBLE (-3325 2975);
FORCEPROP 1 LAST PATH I292
J 0
(-3652 3100);
DISPLAY 0.872340 (-3652 3100);
PAINT GREEN (-3652 3100);
DISPLAY INVISIBLE (-3652 3100);
FORCEADD TAP..1
(-3450 2950);
FORCEPROP 3 LASTPIN (-3500 2950) SIG_NAME M_B_CPU0_SB_DQS_DN<3>
J 0
(-3490 2960);
DISPLAY 0.659574 (-3490 2960);
PAINT MONO (-3490 2960);
DISPLAY INVISIBLE (-3490 2960);
FORCEPROP 1 LASTPIN (-3500 2950) BN 3
J 0
(-3512 2958);
DISPLAY 0.489362 (-3512 2958);
PAINT GREEN (-3512 2958);
FORCEPROP 2 LAST CDS_LIB mstr_standard
J 0
(-3450 2950);
DISPLAY 0.723404 (-3450 2950);
PAINT MONO (-3450 2950);
DISPLAY INVISIBLE (-3450 2950);
FORCEPROP 1 LAST BODY_TYPE PLUMBING
J 0
(-3450 3000);
DISPLAY 0.872340 (-3450 3000);
PAINT GREEN (-3450 3000);
DISPLAY INVISIBLE (-3450 3000);
FORCEPROP 1 LAST HDL_TAP TRUE
J 0
(-3125 2825);
DISPLAY 0.872340 (-3125 2825);
DISPLAY INVISIBLE (-3125 2825);
FORCEPROP 1 LAST PATH I293
J 0
(-3452 2950);
DISPLAY 0.872340 (-3452 2950);
PAINT GREEN (-3452 2950);
DISPLAY INVISIBLE (-3452 2950);
FORCEADD TAP..1
(-3450 3050);
FORCEPROP 3 LASTPIN (-3500 3050) SIG_NAME M_B_CPU0_SB_DQS_DN<4>
J 0
(-3490 3060);
DISPLAY 0.659574 (-3490 3060);
PAINT MONO (-3490 3060);
DISPLAY INVISIBLE (-3490 3060);
FORCEPROP 1 LASTPIN (-3500 3050) BN 4
J 0
(-3512 3058);
DISPLAY 0.489362 (-3512 3058);
PAINT GREEN (-3512 3058);
FORCEPROP 2 LAST CDS_LIB mstr_standard
J 0
(-3450 3050);
DISPLAY 0.723404 (-3450 3050);
PAINT MONO (-3450 3050);
DISPLAY INVISIBLE (-3450 3050);
FORCEPROP 1 LAST BODY_TYPE PLUMBING
J 0
(-3450 3100);
DISPLAY 0.872340 (-3450 3100);
PAINT GREEN (-3450 3100);
DISPLAY INVISIBLE (-3450 3100);
FORCEPROP 1 LAST HDL_TAP TRUE
J 0
(-3125 2925);
DISPLAY 0.872340 (-3125 2925);
DISPLAY INVISIBLE (-3125 2925);
FORCEPROP 1 LAST PATH I294
J 0
(-3452 3050);
DISPLAY 0.872340 (-3452 3050);
PAINT GREEN (-3452 3050);
DISPLAY INVISIBLE (-3452 3050);
FORCEADD TAP..1
(-3650 3200);
FORCEPROP 3 LASTPIN (-3700 3200) SIG_NAME M_B_CPU0_SB_DQS_DP<5>
J 0
(-3690 3210);
DISPLAY 0.659574 (-3690 3210);
PAINT MONO (-3690 3210);
DISPLAY INVISIBLE (-3690 3210);
FORCEPROP 1 LASTPIN (-3700 3200) BN 5
J 0
(-3712 3208);
DISPLAY 0.489362 (-3712 3208);
PAINT GREEN (-3712 3208);
FORCEPROP 2 LAST CDS_LIB mstr_standard
J 0
(-3650 3200);
DISPLAY 0.723404 (-3650 3200);
PAINT MONO (-3650 3200);
DISPLAY INVISIBLE (-3650 3200);
FORCEPROP 1 LAST BODY_TYPE PLUMBING
J 0
(-3650 3250);
DISPLAY 0.872340 (-3650 3250);
PAINT GREEN (-3650 3250);
DISPLAY INVISIBLE (-3650 3250);
FORCEPROP 1 LAST HDL_TAP TRUE
J 0
(-3325 3075);
DISPLAY 0.872340 (-3325 3075);
DISPLAY INVISIBLE (-3325 3075);
FORCEPROP 1 LAST PATH I295
J 0
(-3652 3200);
DISPLAY 0.872340 (-3652 3200);
PAINT GREEN (-3652 3200);
DISPLAY INVISIBLE (-3652 3200);
FORCEADD TAP..1
(-3650 3300);
FORCEPROP 3 LASTPIN (-3700 3300) SIG_NAME M_B_CPU0_SB_DQS_DP<6>
J 0
(-3690 3310);
DISPLAY 0.659574 (-3690 3310);
PAINT MONO (-3690 3310);
DISPLAY INVISIBLE (-3690 3310);
FORCEPROP 1 LASTPIN (-3700 3300) BN 6
J 0
(-3712 3308);
DISPLAY 0.489362 (-3712 3308);
PAINT GREEN (-3712 3308);
FORCEPROP 2 LAST CDS_LIB mstr_standard
J 0
(-3650 3300);
DISPLAY 0.723404 (-3650 3300);
PAINT MONO (-3650 3300);
DISPLAY INVISIBLE (-3650 3300);
FORCEPROP 1 LAST BODY_TYPE PLUMBING
J 0
(-3650 3350);
DISPLAY 0.872340 (-3650 3350);
PAINT GREEN (-3650 3350);
DISPLAY INVISIBLE (-3650 3350);
FORCEPROP 1 LAST HDL_TAP TRUE
J 0
(-3325 3175);
DISPLAY 0.872340 (-3325 3175);
DISPLAY INVISIBLE (-3325 3175);
FORCEPROP 1 LAST PATH I296
J 0
(-3652 3300);
DISPLAY 0.872340 (-3652 3300);
PAINT GREEN (-3652 3300);
DISPLAY INVISIBLE (-3652 3300);
FORCEADD TAP..1
(-3450 3350);
FORCEPROP 3 LASTPIN (-3500 3350) SIG_NAME M_B_CPU0_SB_DQS_DN<7>
J 0
(-3490 3360);
DISPLAY 0.659574 (-3490 3360);
PAINT MONO (-3490 3360);
DISPLAY INVISIBLE (-3490 3360);
FORCEPROP 1 LASTPIN (-3500 3350) BN 7
J 0
(-3512 3358);
DISPLAY 0.489362 (-3512 3358);
PAINT GREEN (-3512 3358);
FORCEPROP 2 LAST CDS_LIB mstr_standard
J 0
(-3450 3350);
DISPLAY 0.723404 (-3450 3350);
PAINT MONO (-3450 3350);
DISPLAY INVISIBLE (-3450 3350);
FORCEPROP 1 LAST BODY_TYPE PLUMBING
J 0
(-3450 3400);
DISPLAY 0.872340 (-3450 3400);
PAINT GREEN (-3450 3400);
DISPLAY INVISIBLE (-3450 3400);
FORCEPROP 1 LAST HDL_TAP TRUE
J 0
(-3125 3225);
DISPLAY 0.872340 (-3125 3225);
DISPLAY INVISIBLE (-3125 3225);
FORCEPROP 1 LAST PATH I297
J 0
(-3452 3350);
DISPLAY 0.872340 (-3452 3350);
PAINT GREEN (-3452 3350);
DISPLAY INVISIBLE (-3452 3350);
FORCEADD TAP..1
(-3450 3250);
FORCEPROP 3 LASTPIN (-3500 3250) SIG_NAME M_B_CPU0_SB_DQS_DN<6>
J 0
(-3490 3260);
DISPLAY 0.659574 (-3490 3260);
PAINT MONO (-3490 3260);
DISPLAY INVISIBLE (-3490 3260);
FORCEPROP 1 LASTPIN (-3500 3250) BN 6
J 0
(-3512 3258);
DISPLAY 0.489362 (-3512 3258);
PAINT GREEN (-3512 3258);
FORCEPROP 2 LAST CDS_LIB mstr_standard
J 0
(-3450 3250);
DISPLAY 0.723404 (-3450 3250);
PAINT MONO (-3450 3250);
DISPLAY INVISIBLE (-3450 3250);
FORCEPROP 1 LAST BODY_TYPE PLUMBING
J 0
(-3450 3300);
DISPLAY 0.872340 (-3450 3300);
PAINT GREEN (-3450 3300);
DISPLAY INVISIBLE (-3450 3300);
FORCEPROP 1 LAST HDL_TAP TRUE
J 0
(-3125 3125);
DISPLAY 0.872340 (-3125 3125);
DISPLAY INVISIBLE (-3125 3125);
FORCEPROP 1 LAST PATH I298
J 0
(-3452 3250);
DISPLAY 0.872340 (-3452 3250);
PAINT GREEN (-3452 3250);
DISPLAY INVISIBLE (-3452 3250);
FORCEADD TAP..1
(-3450 3150);
FORCEPROP 3 LASTPIN (-3500 3150) SIG_NAME M_B_CPU0_SB_DQS_DN<5>
J 0
(-3490 3160);
DISPLAY 0.659574 (-3490 3160);
PAINT MONO (-3490 3160);
DISPLAY INVISIBLE (-3490 3160);
FORCEPROP 1 LASTPIN (-3500 3150) BN 5
J 0
(-3512 3158);
DISPLAY 0.489362 (-3512 3158);
PAINT GREEN (-3512 3158);
FORCEPROP 2 LAST CDS_LIB mstr_standard
J 0
(-3450 3150);
DISPLAY 0.723404 (-3450 3150);
PAINT MONO (-3450 3150);
DISPLAY INVISIBLE (-3450 3150);
FORCEPROP 1 LAST BODY_TYPE PLUMBING
J 0
(-3450 3200);
DISPLAY 0.872340 (-3450 3200);
PAINT GREEN (-3450 3200);
DISPLAY INVISIBLE (-3450 3200);
FORCEPROP 1 LAST HDL_TAP TRUE
J 0
(-3125 3025);
DISPLAY 0.872340 (-3125 3025);
DISPLAY INVISIBLE (-3125 3025);
FORCEPROP 1 LAST PATH I299
J 0
(-3452 3150);
DISPLAY 0.872340 (-3452 3150);
PAINT GREEN (-3452 3150);
DISPLAY INVISIBLE (-3452 3150);
FORCEADD TAP..1
(-3650 3400);
FORCEPROP 3 LASTPIN (-3700 3400) SIG_NAME M_B_CPU0_SB_DQS_DP<7>
J 0
(-3690 3410);
DISPLAY 0.659574 (-3690 3410);
PAINT MONO (-3690 3410);
DISPLAY INVISIBLE (-3690 3410);
FORCEPROP 1 LASTPIN (-3700 3400) BN 7
J 0
(-3712 3408);
DISPLAY 0.489362 (-3712 3408);
PAINT GREEN (-3712 3408);
FORCEPROP 2 LAST CDS_LIB mstr_standard
J 0
(-3650 3400);
DISPLAY 0.723404 (-3650 3400);
PAINT MONO (-3650 3400);
DISPLAY INVISIBLE (-3650 3400);
FORCEPROP 1 LAST BODY_TYPE PLUMBING
J 0
(-3650 3450);
DISPLAY 0.872340 (-3650 3450);
PAINT GREEN (-3650 3450);
DISPLAY INVISIBLE (-3650 3450);
FORCEPROP 1 LAST HDL_TAP TRUE
J 0
(-3325 3275);
DISPLAY 0.872340 (-3325 3275);
DISPLAY INVISIBLE (-3325 3275);
FORCEPROP 1 LAST PATH I300
J 0
(-3652 3400);
DISPLAY 0.872340 (-3652 3400);
PAINT GREEN (-3652 3400);
DISPLAY INVISIBLE (-3652 3400);
FORCEADD TAP..1
(-3650 3500);
FORCEPROP 3 LASTPIN (-3700 3500) SIG_NAME M_B_CPU0_SB_DQS_DP<8>
J 0
(-3690 3510);
DISPLAY 0.659574 (-3690 3510);
PAINT MONO (-3690 3510);
DISPLAY INVISIBLE (-3690 3510);
FORCEPROP 1 LASTPIN (-3700 3500) BN 8
J 0
(-3712 3508);
DISPLAY 0.489362 (-3712 3508);
PAINT GREEN (-3712 3508);
FORCEPROP 2 LAST CDS_LIB mstr_standard
J 0
(-3650 3500);
DISPLAY 0.723404 (-3650 3500);
PAINT MONO (-3650 3500);
DISPLAY INVISIBLE (-3650 3500);
FORCEPROP 1 LAST BODY_TYPE PLUMBING
J 0
(-3650 3550);
DISPLAY 0.872340 (-3650 3550);
PAINT GREEN (-3650 3550);
DISPLAY INVISIBLE (-3650 3550);
FORCEPROP 1 LAST HDL_TAP TRUE
J 0
(-3325 3375);
DISPLAY 0.872340 (-3325 3375);
DISPLAY INVISIBLE (-3325 3375);
FORCEPROP 1 LAST PATH I301
J 0
(-3652 3500);
DISPLAY 0.872340 (-3652 3500);
PAINT GREEN (-3652 3500);
DISPLAY INVISIBLE (-3652 3500);
FORCEADD TAP..1
(-3650 3600);
FORCEPROP 3 LASTPIN (-3700 3600) SIG_NAME M_B_CPU0_SB_DQS_DP<9>
J 0
(-3690 3610);
DISPLAY 0.659574 (-3690 3610);
PAINT MONO (-3690 3610);
DISPLAY INVISIBLE (-3690 3610);
FORCEPROP 1 LASTPIN (-3700 3600) BN 9
J 0
(-3712 3608);
DISPLAY 0.489362 (-3712 3608);
PAINT GREEN (-3712 3608);
FORCEPROP 2 LAST CDS_LIB mstr_standard
J 0
(-3650 3600);
DISPLAY 0.723404 (-3650 3600);
PAINT MONO (-3650 3600);
DISPLAY INVISIBLE (-3650 3600);
FORCEPROP 1 LAST BODY_TYPE PLUMBING
J 0
(-3650 3650);
DISPLAY 0.872340 (-3650 3650);
PAINT GREEN (-3650 3650);
DISPLAY INVISIBLE (-3650 3650);
FORCEPROP 1 LAST HDL_TAP TRUE
J 0
(-3325 3475);
DISPLAY 0.872340 (-3325 3475);
DISPLAY INVISIBLE (-3325 3475);
FORCEPROP 1 LAST PATH I302
J 0
(-3652 3600);
DISPLAY 0.872340 (-3652 3600);
PAINT GREEN (-3652 3600);
DISPLAY INVISIBLE (-3652 3600);
FORCEADD TAP..1
(-3450 3450);
FORCEPROP 3 LASTPIN (-3500 3450) SIG_NAME M_B_CPU0_SB_DQS_DN<8>
J 0
(-3490 3460);
DISPLAY 0.659574 (-3490 3460);
PAINT MONO (-3490 3460);
DISPLAY INVISIBLE (-3490 3460);
FORCEPROP 1 LASTPIN (-3500 3450) BN 8
J 0
(-3512 3458);
DISPLAY 0.489362 (-3512 3458);
PAINT GREEN (-3512 3458);
FORCEPROP 2 LAST CDS_LIB mstr_standard
J 0
(-3450 3450);
DISPLAY 0.723404 (-3450 3450);
PAINT MONO (-3450 3450);
DISPLAY INVISIBLE (-3450 3450);
FORCEPROP 1 LAST BODY_TYPE PLUMBING
J 0
(-3450 3500);
DISPLAY 0.872340 (-3450 3500);
PAINT GREEN (-3450 3500);
DISPLAY INVISIBLE (-3450 3500);
FORCEPROP 1 LAST HDL_TAP TRUE
J 0
(-3125 3325);
DISPLAY 0.872340 (-3125 3325);
DISPLAY INVISIBLE (-3125 3325);
FORCEPROP 1 LAST PATH I303
J 0
(-3452 3450);
DISPLAY 0.872340 (-3452 3450);
PAINT GREEN (-3452 3450);
DISPLAY INVISIBLE (-3452 3450);
FORCEADD TAP..1
(-3450 3550);
FORCEPROP 3 LASTPIN (-3500 3550) SIG_NAME M_B_CPU0_SB_DQS_DN<9>
J 0
(-3490 3560);
DISPLAY 0.659574 (-3490 3560);
PAINT MONO (-3490 3560);
DISPLAY INVISIBLE (-3490 3560);
FORCEPROP 1 LASTPIN (-3500 3550) BN 9
J 0
(-3512 3558);
DISPLAY 0.489362 (-3512 3558);
PAINT GREEN (-3512 3558);
FORCEPROP 2 LAST CDS_LIB mstr_standard
J 0
(-3450 3550);
DISPLAY 0.723404 (-3450 3550);
PAINT MONO (-3450 3550);
DISPLAY INVISIBLE (-3450 3550);
FORCEPROP 1 LAST BODY_TYPE PLUMBING
J 0
(-3450 3600);
DISPLAY 0.872340 (-3450 3600);
PAINT GREEN (-3450 3600);
DISPLAY INVISIBLE (-3450 3600);
FORCEPROP 1 LAST HDL_TAP TRUE
J 0
(-3125 3425);
DISPLAY 0.872340 (-3125 3425);
DISPLAY INVISIBLE (-3125 3425);
FORCEPROP 1 LAST PATH I304
J 0
(-3452 3550);
DISPLAY 0.872340 (-3452 3550);
PAINT GREEN (-3452 3550);
DISPLAY INVISIBLE (-3452 3550);
FORCEADD TAP..1
(-3650 3750);
FORCEPROP 3 LASTPIN (-3700 3750) SIG_NAME M_B_CPU0_SA_DQS_DP<0>
J 0
(-3690 3760);
DISPLAY 0.659574 (-3690 3760);
PAINT MONO (-3690 3760);
DISPLAY INVISIBLE (-3690 3760);
FORCEPROP 1 LASTPIN (-3700 3750) BN 0
J 0
(-3712 3758);
DISPLAY 0.489362 (-3712 3758);
PAINT GREEN (-3712 3758);
FORCEPROP 2 LAST CDS_LIB mstr_standard
J 0
(-3650 3750);
DISPLAY 0.723404 (-3650 3750);
PAINT MONO (-3650 3750);
DISPLAY INVISIBLE (-3650 3750);
FORCEPROP 1 LAST BODY_TYPE PLUMBING
J 0
(-3650 3800);
DISPLAY 0.872340 (-3650 3800);
PAINT GREEN (-3650 3800);
DISPLAY INVISIBLE (-3650 3800);
FORCEPROP 1 LAST HDL_TAP TRUE
J 0
(-3325 3625);
DISPLAY 0.872340 (-3325 3625);
DISPLAY INVISIBLE (-3325 3625);
FORCEPROP 1 LAST PATH I305
J 0
(-3652 3750);
DISPLAY 0.872340 (-3652 3750);
PAINT GREEN (-3652 3750);
DISPLAY INVISIBLE (-3652 3750);
FORCEADD TAP..1
(-3650 3850);
FORCEPROP 3 LASTPIN (-3700 3850) SIG_NAME M_B_CPU0_SA_DQS_DP<1>
J 0
(-3690 3860);
DISPLAY 0.659574 (-3690 3860);
PAINT MONO (-3690 3860);
DISPLAY INVISIBLE (-3690 3860);
FORCEPROP 1 LASTPIN (-3700 3850) BN 1
J 0
(-3712 3858);
DISPLAY 0.489362 (-3712 3858);
PAINT GREEN (-3712 3858);
FORCEPROP 2 LAST CDS_LIB mstr_standard
J 0
(-3650 3850);
DISPLAY 0.723404 (-3650 3850);
PAINT MONO (-3650 3850);
DISPLAY INVISIBLE (-3650 3850);
FORCEPROP 1 LAST BODY_TYPE PLUMBING
J 0
(-3650 3900);
DISPLAY 0.872340 (-3650 3900);
PAINT GREEN (-3650 3900);
DISPLAY INVISIBLE (-3650 3900);
FORCEPROP 1 LAST HDL_TAP TRUE
J 0
(-3325 3725);
DISPLAY 0.872340 (-3325 3725);
DISPLAY INVISIBLE (-3325 3725);
FORCEPROP 1 LAST PATH I306
J 0
(-3652 3850);
DISPLAY 0.872340 (-3652 3850);
PAINT GREEN (-3652 3850);
DISPLAY INVISIBLE (-3652 3850);
FORCEADD TAP..1
(-3450 3700);
FORCEPROP 3 LASTPIN (-3500 3700) SIG_NAME M_B_CPU0_SA_DQS_DN<0>
J 0
(-3490 3710);
DISPLAY 0.659574 (-3490 3710);
PAINT MONO (-3490 3710);
DISPLAY INVISIBLE (-3490 3710);
FORCEPROP 1 LASTPIN (-3500 3700) BN 0
J 0
(-3512 3708);
DISPLAY 0.489362 (-3512 3708);
PAINT GREEN (-3512 3708);
FORCEPROP 2 LAST CDS_LIB mstr_standard
J 0
(-3450 3700);
DISPLAY 0.723404 (-3450 3700);
PAINT MONO (-3450 3700);
DISPLAY INVISIBLE (-3450 3700);
FORCEPROP 1 LAST BODY_TYPE PLUMBING
J 0
(-3450 3750);
DISPLAY 0.872340 (-3450 3750);
PAINT GREEN (-3450 3750);
DISPLAY INVISIBLE (-3450 3750);
FORCEPROP 1 LAST HDL_TAP TRUE
J 0
(-3125 3575);
DISPLAY 0.872340 (-3125 3575);
DISPLAY INVISIBLE (-3125 3575);
FORCEPROP 1 LAST PATH I307
J 0
(-3452 3700);
DISPLAY 0.872340 (-3452 3700);
PAINT GREEN (-3452 3700);
DISPLAY INVISIBLE (-3452 3700);
FORCEADD TAP..1
(-3450 3800);
FORCEPROP 3 LASTPIN (-3500 3800) SIG_NAME M_B_CPU0_SA_DQS_DN<1>
J 0
(-3490 3810);
DISPLAY 0.659574 (-3490 3810);
PAINT MONO (-3490 3810);
DISPLAY INVISIBLE (-3490 3810);
FORCEPROP 1 LASTPIN (-3500 3800) BN 1
J 0
(-3512 3808);
DISPLAY 0.489362 (-3512 3808);
PAINT GREEN (-3512 3808);
FORCEPROP 2 LAST CDS_LIB mstr_standard
J 0
(-3450 3800);
DISPLAY 0.723404 (-3450 3800);
PAINT MONO (-3450 3800);
DISPLAY INVISIBLE (-3450 3800);
FORCEPROP 1 LAST BODY_TYPE PLUMBING
J 0
(-3450 3850);
DISPLAY 0.872340 (-3450 3850);
PAINT GREEN (-3450 3850);
DISPLAY INVISIBLE (-3450 3850);
FORCEPROP 1 LAST HDL_TAP TRUE
J 0
(-3125 3675);
DISPLAY 0.872340 (-3125 3675);
DISPLAY INVISIBLE (-3125 3675);
FORCEPROP 1 LAST PATH I308
J 0
(-3452 3800);
DISPLAY 0.872340 (-3452 3800);
PAINT GREEN (-3452 3800);
DISPLAY INVISIBLE (-3452 3800);
FORCEADD TAP..1
(-3650 3950);
FORCEPROP 3 LASTPIN (-3700 3950) SIG_NAME M_B_CPU0_SA_DQS_DP<2>
J 0
(-3690 3960);
DISPLAY 0.659574 (-3690 3960);
PAINT MONO (-3690 3960);
DISPLAY INVISIBLE (-3690 3960);
FORCEPROP 1 LASTPIN (-3700 3950) BN 2
J 0
(-3712 3958);
DISPLAY 0.489362 (-3712 3958);
PAINT GREEN (-3712 3958);
FORCEPROP 2 LAST CDS_LIB mstr_standard
J 0
(-3650 3950);
DISPLAY 0.723404 (-3650 3950);
PAINT MONO (-3650 3950);
DISPLAY INVISIBLE (-3650 3950);
FORCEPROP 1 LAST BODY_TYPE PLUMBING
J 0
(-3650 4000);
DISPLAY 0.872340 (-3650 4000);
PAINT GREEN (-3650 4000);
DISPLAY INVISIBLE (-3650 4000);
FORCEPROP 1 LAST HDL_TAP TRUE
J 0
(-3325 3825);
DISPLAY 0.872340 (-3325 3825);
DISPLAY INVISIBLE (-3325 3825);
FORCEPROP 1 LAST PATH I309
J 0
(-3652 3950);
DISPLAY 0.872340 (-3652 3950);
PAINT GREEN (-3652 3950);
DISPLAY INVISIBLE (-3652 3950);
FORCEADD TAP..1
(-3650 4050);
FORCEPROP 3 LASTPIN (-3700 4050) SIG_NAME M_B_CPU0_SA_DQS_DP<3>
J 0
(-3690 4060);
DISPLAY 0.659574 (-3690 4060);
PAINT MONO (-3690 4060);
DISPLAY INVISIBLE (-3690 4060);
FORCEPROP 1 LASTPIN (-3700 4050) BN 3
J 0
(-3712 4058);
DISPLAY 0.489362 (-3712 4058);
PAINT GREEN (-3712 4058);
FORCEPROP 2 LAST CDS_LIB mstr_standard
J 0
(-3650 4050);
DISPLAY 0.723404 (-3650 4050);
PAINT MONO (-3650 4050);
DISPLAY INVISIBLE (-3650 4050);
FORCEPROP 1 LAST BODY_TYPE PLUMBING
J 0
(-3650 4100);
DISPLAY 0.872340 (-3650 4100);
PAINT GREEN (-3650 4100);
DISPLAY INVISIBLE (-3650 4100);
FORCEPROP 1 LAST HDL_TAP TRUE
J 0
(-3325 3925);
DISPLAY 0.872340 (-3325 3925);
DISPLAY INVISIBLE (-3325 3925);
FORCEPROP 1 LAST PATH I310
J 0
(-3652 4050);
DISPLAY 0.872340 (-3652 4050);
PAINT GREEN (-3652 4050);
DISPLAY INVISIBLE (-3652 4050);
FORCEADD TAP..1
(-3450 3900);
FORCEPROP 3 LASTPIN (-3500 3900) SIG_NAME M_B_CPU0_SA_DQS_DN<2>
J 0
(-3490 3910);
DISPLAY 0.659574 (-3490 3910);
PAINT MONO (-3490 3910);
DISPLAY INVISIBLE (-3490 3910);
FORCEPROP 1 LASTPIN (-3500 3900) BN 2
J 0
(-3512 3908);
DISPLAY 0.489362 (-3512 3908);
PAINT GREEN (-3512 3908);
FORCEPROP 2 LAST CDS_LIB mstr_standard
J 0
(-3450 3900);
DISPLAY 0.723404 (-3450 3900);
PAINT MONO (-3450 3900);
DISPLAY INVISIBLE (-3450 3900);
FORCEPROP 1 LAST BODY_TYPE PLUMBING
J 0
(-3450 3950);
DISPLAY 0.872340 (-3450 3950);
PAINT GREEN (-3450 3950);
DISPLAY INVISIBLE (-3450 3950);
FORCEPROP 1 LAST HDL_TAP TRUE
J 0
(-3125 3775);
DISPLAY 0.872340 (-3125 3775);
DISPLAY INVISIBLE (-3125 3775);
FORCEPROP 1 LAST PATH I311
J 0
(-3452 3900);
DISPLAY 0.872340 (-3452 3900);
PAINT GREEN (-3452 3900);
DISPLAY INVISIBLE (-3452 3900);
FORCEADD TAP..1
(-3450 4000);
FORCEPROP 3 LASTPIN (-3500 4000) SIG_NAME M_B_CPU0_SA_DQS_DN<3>
J 0
(-3490 4010);
DISPLAY 0.659574 (-3490 4010);
PAINT MONO (-3490 4010);
DISPLAY INVISIBLE (-3490 4010);
FORCEPROP 1 LASTPIN (-3500 4000) BN 3
J 0
(-3512 4008);
DISPLAY 0.489362 (-3512 4008);
PAINT GREEN (-3512 4008);
FORCEPROP 2 LAST CDS_LIB mstr_standard
J 0
(-3450 4000);
DISPLAY 0.723404 (-3450 4000);
PAINT MONO (-3450 4000);
DISPLAY INVISIBLE (-3450 4000);
FORCEPROP 1 LAST BODY_TYPE PLUMBING
J 0
(-3450 4050);
DISPLAY 0.872340 (-3450 4050);
PAINT GREEN (-3450 4050);
DISPLAY INVISIBLE (-3450 4050);
FORCEPROP 1 LAST HDL_TAP TRUE
J 0
(-3125 3875);
DISPLAY 0.872340 (-3125 3875);
DISPLAY INVISIBLE (-3125 3875);
FORCEPROP 1 LAST PATH I312
J 0
(-3452 4000);
DISPLAY 0.872340 (-3452 4000);
PAINT GREEN (-3452 4000);
DISPLAY INVISIBLE (-3452 4000);
FORCEADD TAP..1
(-3450 4100);
FORCEPROP 3 LASTPIN (-3500 4100) SIG_NAME M_B_CPU0_SA_DQS_DN<4>
J 0
(-3490 4110);
DISPLAY 0.659574 (-3490 4110);
PAINT MONO (-3490 4110);
DISPLAY INVISIBLE (-3490 4110);
FORCEPROP 1 LASTPIN (-3500 4100) BN 4
J 0
(-3512 4108);
DISPLAY 0.489362 (-3512 4108);
PAINT GREEN (-3512 4108);
FORCEPROP 2 LAST CDS_LIB mstr_standard
J 0
(-3450 4100);
DISPLAY 0.723404 (-3450 4100);
PAINT MONO (-3450 4100);
DISPLAY INVISIBLE (-3450 4100);
FORCEPROP 1 LAST BODY_TYPE PLUMBING
J 0
(-3450 4150);
DISPLAY 0.872340 (-3450 4150);
PAINT GREEN (-3450 4150);
DISPLAY INVISIBLE (-3450 4150);
FORCEPROP 1 LAST HDL_TAP TRUE
J 0
(-3125 3975);
DISPLAY 0.872340 (-3125 3975);
DISPLAY INVISIBLE (-3125 3975);
FORCEPROP 1 LAST PATH I313
J 0
(-3452 4100);
DISPLAY 0.872340 (-3452 4100);
PAINT GREEN (-3452 4100);
DISPLAY INVISIBLE (-3452 4100);
FORCEADD OFFPAGE..2
(-2650 3600);
FORCEPROP 2 LAST $XR0 11 
J 0
(-2461 3600);
DISPLAY 0.638298 (-2461 3600);
PAINT MONO (-2461 3600);
FORCEPROP 2 LAST CDS_LIB mstr_standard
J 0
(-2650 3600);
DISPLAY 0.723404 (-2650 3600);
PAINT MONO (-2650 3600);
DISPLAY INVISIBLE (-2650 3600);
FORCEPROP 1 LAST OFFPAGE TRUE
J 0
(-2325 3475);
DISPLAY 0.723404 (-2325 3475);
PAINT GREEN (-2325 3475);
DISPLAY INVISIBLE (-2325 3475);
FORCEPROP 1 LAST COMMENT_BODY TRUE
J 0
(-2695 3505);
DISPLAY 0.872340 (-2695 3505);
PAINT GREEN (-2695 3505);
DISPLAY INVISIBLE (-2695 3505);
FORCEPROP 2 LAST PATH I314
J 0
(-2350 3650);
DISPLAY 0.808511 (-2350 3650);
DISPLAY INVISIBLE (-2350 3650);
FORCEADD OFFPAGE..2
(-2650 3650);
FORCEPROP 2 LAST $XR0 11 
J 0
(-2461 3650);
DISPLAY 0.638298 (-2461 3650);
PAINT MONO (-2461 3650);
FORCEPROP 2 LAST CDS_LIB mstr_standard
J 0
(-2650 3650);
DISPLAY 0.723404 (-2650 3650);
PAINT MONO (-2650 3650);
DISPLAY INVISIBLE (-2650 3650);
FORCEPROP 1 LAST OFFPAGE TRUE
J 0
(-2325 3525);
DISPLAY 0.723404 (-2325 3525);
PAINT GREEN (-2325 3525);
DISPLAY INVISIBLE (-2325 3525);
FORCEPROP 1 LAST COMMENT_BODY TRUE
J 0
(-2695 3555);
DISPLAY 0.872340 (-2695 3555);
PAINT GREEN (-2695 3555);
DISPLAY INVISIBLE (-2695 3555);
FORCEPROP 2 LAST PATH I315
J 0
(-2350 3700);
DISPLAY 0.808511 (-2350 3700);
DISPLAY INVISIBLE (-2350 3700);
FORCEADD TAP..1
(-3650 4150);
FORCEPROP 3 LASTPIN (-3700 4150) SIG_NAME M_B_CPU0_SA_DQS_DP<4>
J 0
(-3690 4160);
DISPLAY 0.659574 (-3690 4160);
PAINT MONO (-3690 4160);
DISPLAY INVISIBLE (-3690 4160);
FORCEPROP 1 LASTPIN (-3700 4150) BN 4
J 0
(-3712 4158);
DISPLAY 0.489362 (-3712 4158);
PAINT GREEN (-3712 4158);
FORCEPROP 2 LAST CDS_LIB mstr_standard
J 0
(-3650 4150);
DISPLAY 0.723404 (-3650 4150);
PAINT MONO (-3650 4150);
DISPLAY INVISIBLE (-3650 4150);
FORCEPROP 1 LAST BODY_TYPE PLUMBING
J 0
(-3650 4200);
DISPLAY 0.872340 (-3650 4200);
PAINT GREEN (-3650 4200);
DISPLAY INVISIBLE (-3650 4200);
FORCEPROP 1 LAST HDL_TAP TRUE
J 0
(-3325 4025);
DISPLAY 0.872340 (-3325 4025);
DISPLAY INVISIBLE (-3325 4025);
FORCEPROP 1 LAST PATH I316
J 0
(-3652 4150);
DISPLAY 0.872340 (-3652 4150);
PAINT GREEN (-3652 4150);
DISPLAY INVISIBLE (-3652 4150);
FORCEADD TAP..1
(-3650 4250);
FORCEPROP 3 LASTPIN (-3700 4250) SIG_NAME M_B_CPU0_SA_DQS_DP<5>
J 0
(-3690 4260);
DISPLAY 0.659574 (-3690 4260);
PAINT MONO (-3690 4260);
DISPLAY INVISIBLE (-3690 4260);
FORCEPROP 1 LASTPIN (-3700 4250) BN 5
J 0
(-3712 4258);
DISPLAY 0.489362 (-3712 4258);
PAINT GREEN (-3712 4258);
FORCEPROP 2 LAST CDS_LIB mstr_standard
J 0
(-3650 4250);
DISPLAY 0.723404 (-3650 4250);
PAINT MONO (-3650 4250);
DISPLAY INVISIBLE (-3650 4250);
FORCEPROP 1 LAST BODY_TYPE PLUMBING
J 0
(-3650 4300);
DISPLAY 0.872340 (-3650 4300);
PAINT GREEN (-3650 4300);
DISPLAY INVISIBLE (-3650 4300);
FORCEPROP 1 LAST HDL_TAP TRUE
J 0
(-3325 4125);
DISPLAY 0.872340 (-3325 4125);
DISPLAY INVISIBLE (-3325 4125);
FORCEPROP 1 LAST PATH I317
J 0
(-3652 4250);
DISPLAY 0.872340 (-3652 4250);
PAINT GREEN (-3652 4250);
DISPLAY INVISIBLE (-3652 4250);
FORCEADD TAP..1
(-3650 4350);
FORCEPROP 3 LASTPIN (-3700 4350) SIG_NAME M_B_CPU0_SA_DQS_DP<6>
J 0
(-3690 4360);
DISPLAY 0.659574 (-3690 4360);
PAINT MONO (-3690 4360);
DISPLAY INVISIBLE (-3690 4360);
FORCEPROP 1 LASTPIN (-3700 4350) BN 6
J 0
(-3712 4358);
DISPLAY 0.489362 (-3712 4358);
PAINT GREEN (-3712 4358);
FORCEPROP 2 LAST CDS_LIB mstr_standard
J 0
(-3650 4350);
DISPLAY 0.723404 (-3650 4350);
PAINT MONO (-3650 4350);
DISPLAY INVISIBLE (-3650 4350);
FORCEPROP 1 LAST BODY_TYPE PLUMBING
J 0
(-3650 4400);
DISPLAY 0.872340 (-3650 4400);
PAINT GREEN (-3650 4400);
DISPLAY INVISIBLE (-3650 4400);
FORCEPROP 1 LAST HDL_TAP TRUE
J 0
(-3325 4225);
DISPLAY 0.872340 (-3325 4225);
DISPLAY INVISIBLE (-3325 4225);
FORCEPROP 1 LAST PATH I318
J 0
(-3652 4350);
DISPLAY 0.872340 (-3652 4350);
PAINT GREEN (-3652 4350);
DISPLAY INVISIBLE (-3652 4350);
FORCEADD TAP..1
(-3450 4400);
FORCEPROP 3 LASTPIN (-3500 4400) SIG_NAME M_B_CPU0_SA_DQS_DN<7>
J 0
(-3490 4410);
DISPLAY 0.659574 (-3490 4410);
PAINT MONO (-3490 4410);
DISPLAY INVISIBLE (-3490 4410);
FORCEPROP 1 LASTPIN (-3500 4400) BN 7
J 0
(-3512 4408);
DISPLAY 0.489362 (-3512 4408);
PAINT GREEN (-3512 4408);
FORCEPROP 2 LAST CDS_LIB mstr_standard
J 0
(-3450 4400);
DISPLAY 0.723404 (-3450 4400);
PAINT MONO (-3450 4400);
DISPLAY INVISIBLE (-3450 4400);
FORCEPROP 1 LAST BODY_TYPE PLUMBING
J 0
(-3450 4450);
DISPLAY 0.872340 (-3450 4450);
PAINT GREEN (-3450 4450);
DISPLAY INVISIBLE (-3450 4450);
FORCEPROP 1 LAST HDL_TAP TRUE
J 0
(-3125 4275);
DISPLAY 0.872340 (-3125 4275);
DISPLAY INVISIBLE (-3125 4275);
FORCEPROP 1 LAST PATH I319
J 0
(-3452 4400);
DISPLAY 0.872340 (-3452 4400);
PAINT GREEN (-3452 4400);
DISPLAY INVISIBLE (-3452 4400);
FORCEADD TAP..1
(-3450 4300);
FORCEPROP 3 LASTPIN (-3500 4300) SIG_NAME M_B_CPU0_SA_DQS_DN<6>
J 0
(-3490 4310);
DISPLAY 0.659574 (-3490 4310);
PAINT MONO (-3490 4310);
DISPLAY INVISIBLE (-3490 4310);
FORCEPROP 1 LASTPIN (-3500 4300) BN 6
J 0
(-3512 4308);
DISPLAY 0.489362 (-3512 4308);
PAINT GREEN (-3512 4308);
FORCEPROP 2 LAST CDS_LIB mstr_standard
J 0
(-3450 4300);
DISPLAY 0.723404 (-3450 4300);
PAINT MONO (-3450 4300);
DISPLAY INVISIBLE (-3450 4300);
FORCEPROP 1 LAST BODY_TYPE PLUMBING
J 0
(-3450 4350);
DISPLAY 0.872340 (-3450 4350);
PAINT GREEN (-3450 4350);
DISPLAY INVISIBLE (-3450 4350);
FORCEPROP 1 LAST HDL_TAP TRUE
J 0
(-3125 4175);
DISPLAY 0.872340 (-3125 4175);
DISPLAY INVISIBLE (-3125 4175);
FORCEPROP 1 LAST PATH I320
J 0
(-3452 4300);
DISPLAY 0.872340 (-3452 4300);
PAINT GREEN (-3452 4300);
DISPLAY INVISIBLE (-3452 4300);
FORCEADD TAP..1
(-3450 4200);
FORCEPROP 3 LASTPIN (-3500 4200) SIG_NAME M_B_CPU0_SA_DQS_DN<5>
J 0
(-3490 4210);
DISPLAY 0.659574 (-3490 4210);
PAINT MONO (-3490 4210);
DISPLAY INVISIBLE (-3490 4210);
FORCEPROP 1 LASTPIN (-3500 4200) BN 5
J 0
(-3512 4208);
DISPLAY 0.489362 (-3512 4208);
PAINT GREEN (-3512 4208);
FORCEPROP 2 LAST CDS_LIB mstr_standard
J 0
(-3450 4200);
DISPLAY 0.723404 (-3450 4200);
PAINT MONO (-3450 4200);
DISPLAY INVISIBLE (-3450 4200);
FORCEPROP 1 LAST BODY_TYPE PLUMBING
J 0
(-3450 4250);
DISPLAY 0.872340 (-3450 4250);
PAINT GREEN (-3450 4250);
DISPLAY INVISIBLE (-3450 4250);
FORCEPROP 1 LAST HDL_TAP TRUE
J 0
(-3125 4075);
DISPLAY 0.872340 (-3125 4075);
DISPLAY INVISIBLE (-3125 4075);
FORCEPROP 1 LAST PATH I321
J 0
(-3452 4200);
DISPLAY 0.872340 (-3452 4200);
PAINT GREEN (-3452 4200);
DISPLAY INVISIBLE (-3452 4200);
FORCEADD TAP..1
(-3650 4450);
FORCEPROP 3 LASTPIN (-3700 4450) SIG_NAME M_B_CPU0_SA_DQS_DP<7>
J 0
(-3690 4460);
DISPLAY 0.659574 (-3690 4460);
PAINT MONO (-3690 4460);
DISPLAY INVISIBLE (-3690 4460);
FORCEPROP 1 LASTPIN (-3700 4450) BN 7
J 0
(-3712 4458);
DISPLAY 0.489362 (-3712 4458);
PAINT GREEN (-3712 4458);
FORCEPROP 2 LAST CDS_LIB mstr_standard
J 0
(-3650 4450);
DISPLAY 0.723404 (-3650 4450);
PAINT MONO (-3650 4450);
DISPLAY INVISIBLE (-3650 4450);
FORCEPROP 1 LAST BODY_TYPE PLUMBING
J 0
(-3650 4500);
DISPLAY 0.872340 (-3650 4500);
PAINT GREEN (-3650 4500);
DISPLAY INVISIBLE (-3650 4500);
FORCEPROP 1 LAST HDL_TAP TRUE
J 0
(-3325 4325);
DISPLAY 0.872340 (-3325 4325);
DISPLAY INVISIBLE (-3325 4325);
FORCEPROP 1 LAST PATH I322
J 0
(-3652 4450);
DISPLAY 0.872340 (-3652 4450);
PAINT GREEN (-3652 4450);
DISPLAY INVISIBLE (-3652 4450);
FORCEADD TAP..1
(-3650 4550);
FORCEPROP 3 LASTPIN (-3700 4550) SIG_NAME M_B_CPU0_SA_DQS_DP<8>
J 0
(-3690 4560);
DISPLAY 0.659574 (-3690 4560);
PAINT MONO (-3690 4560);
DISPLAY INVISIBLE (-3690 4560);
FORCEPROP 1 LASTPIN (-3700 4550) BN 8
J 0
(-3712 4558);
DISPLAY 0.489362 (-3712 4558);
PAINT GREEN (-3712 4558);
FORCEPROP 2 LAST CDS_LIB mstr_standard
J 0
(-3650 4550);
DISPLAY 0.723404 (-3650 4550);
PAINT MONO (-3650 4550);
DISPLAY INVISIBLE (-3650 4550);
FORCEPROP 1 LAST BODY_TYPE PLUMBING
J 0
(-3650 4600);
DISPLAY 0.872340 (-3650 4600);
PAINT GREEN (-3650 4600);
DISPLAY INVISIBLE (-3650 4600);
FORCEPROP 1 LAST HDL_TAP TRUE
J 0
(-3325 4425);
DISPLAY 0.872340 (-3325 4425);
DISPLAY INVISIBLE (-3325 4425);
FORCEPROP 1 LAST PATH I323
J 0
(-3652 4550);
DISPLAY 0.872340 (-3652 4550);
PAINT GREEN (-3652 4550);
DISPLAY INVISIBLE (-3652 4550);
FORCEADD TAP..1
(-3650 4650);
FORCEPROP 3 LASTPIN (-3700 4650) SIG_NAME M_B_CPU0_SA_DQS_DP<9>
J 0
(-3690 4660);
DISPLAY 0.659574 (-3690 4660);
PAINT MONO (-3690 4660);
DISPLAY INVISIBLE (-3690 4660);
FORCEPROP 1 LASTPIN (-3700 4650) BN 9
J 0
(-3712 4658);
DISPLAY 0.489362 (-3712 4658);
PAINT GREEN (-3712 4658);
FORCEPROP 2 LAST CDS_LIB mstr_standard
J 0
(-3650 4650);
DISPLAY 0.723404 (-3650 4650);
PAINT MONO (-3650 4650);
DISPLAY INVISIBLE (-3650 4650);
FORCEPROP 1 LAST BODY_TYPE PLUMBING
J 0
(-3650 4700);
DISPLAY 0.872340 (-3650 4700);
PAINT GREEN (-3650 4700);
DISPLAY INVISIBLE (-3650 4700);
FORCEPROP 1 LAST HDL_TAP TRUE
J 0
(-3325 4525);
DISPLAY 0.872340 (-3325 4525);
DISPLAY INVISIBLE (-3325 4525);
FORCEPROP 1 LAST PATH I324
J 0
(-3652 4650);
DISPLAY 0.872340 (-3652 4650);
PAINT GREEN (-3652 4650);
DISPLAY INVISIBLE (-3652 4650);
FORCEADD TAP..1
(-3450 4600);
FORCEPROP 3 LASTPIN (-3500 4600) SIG_NAME M_B_CPU0_SA_DQS_DN<9>
J 0
(-3490 4610);
DISPLAY 0.659574 (-3490 4610);
PAINT MONO (-3490 4610);
DISPLAY INVISIBLE (-3490 4610);
FORCEPROP 1 LASTPIN (-3500 4600) BN 9
J 0
(-3512 4608);
DISPLAY 0.489362 (-3512 4608);
PAINT GREEN (-3512 4608);
FORCEPROP 2 LAST CDS_LIB mstr_standard
J 0
(-3450 4600);
DISPLAY 0.723404 (-3450 4600);
PAINT MONO (-3450 4600);
DISPLAY INVISIBLE (-3450 4600);
FORCEPROP 1 LAST BODY_TYPE PLUMBING
J 0
(-3450 4650);
DISPLAY 0.872340 (-3450 4650);
PAINT GREEN (-3450 4650);
DISPLAY INVISIBLE (-3450 4650);
FORCEPROP 1 LAST HDL_TAP TRUE
J 0
(-3125 4475);
DISPLAY 0.872340 (-3125 4475);
DISPLAY INVISIBLE (-3125 4475);
FORCEPROP 1 LAST PATH I325
J 0
(-3452 4600);
DISPLAY 0.872340 (-3452 4600);
PAINT GREEN (-3452 4600);
DISPLAY INVISIBLE (-3452 4600);
FORCEADD TAP..1
(-3450 4500);
FORCEPROP 3 LASTPIN (-3500 4500) SIG_NAME M_B_CPU0_SA_DQS_DN<8>
J 0
(-3490 4510);
DISPLAY 0.659574 (-3490 4510);
PAINT MONO (-3490 4510);
DISPLAY INVISIBLE (-3490 4510);
FORCEPROP 1 LASTPIN (-3500 4500) BN 8
J 0
(-3512 4508);
DISPLAY 0.489362 (-3512 4508);
PAINT GREEN (-3512 4508);
FORCEPROP 2 LAST CDS_LIB mstr_standard
J 0
(-3450 4500);
DISPLAY 0.723404 (-3450 4500);
PAINT MONO (-3450 4500);
DISPLAY INVISIBLE (-3450 4500);
FORCEPROP 1 LAST BODY_TYPE PLUMBING
J 0
(-3450 4550);
DISPLAY 0.872340 (-3450 4550);
PAINT GREEN (-3450 4550);
DISPLAY INVISIBLE (-3450 4550);
FORCEPROP 1 LAST HDL_TAP TRUE
J 0
(-3125 4375);
DISPLAY 0.872340 (-3125 4375);
DISPLAY INVISIBLE (-3125 4375);
FORCEPROP 1 LAST PATH I326
J 0
(-3452 4500);
DISPLAY 0.872340 (-3452 4500);
PAINT GREEN (-3452 4500);
DISPLAY INVISIBLE (-3452 4500);
FORCEADD OFFPAGE..2
(-2650 4650);
FORCEPROP 2 LAST $XR0 11 
J 0
(-2461 4650);
DISPLAY 0.638298 (-2461 4650);
PAINT MONO (-2461 4650);
FORCEPROP 2 LAST CDS_LIB mstr_standard
J 0
(-2650 4650);
DISPLAY 0.723404 (-2650 4650);
PAINT MONO (-2650 4650);
DISPLAY INVISIBLE (-2650 4650);
FORCEPROP 1 LAST OFFPAGE TRUE
J 0
(-2325 4525);
DISPLAY 0.723404 (-2325 4525);
PAINT GREEN (-2325 4525);
DISPLAY INVISIBLE (-2325 4525);
FORCEPROP 1 LAST COMMENT_BODY TRUE
J 0
(-2695 4555);
DISPLAY 0.872340 (-2695 4555);
PAINT GREEN (-2695 4555);
DISPLAY INVISIBLE (-2695 4555);
FORCEPROP 2 LAST PATH I327
J 0
(-2350 4700);
DISPLAY 0.808511 (-2350 4700);
DISPLAY INVISIBLE (-2350 4700);
FORCEADD OFFPAGE..2
(-2650 4700);
FORCEPROP 2 LAST $XR0 11 
J 0
(-2461 4700);
DISPLAY 0.638298 (-2461 4700);
PAINT MONO (-2461 4700);
FORCEPROP 2 LAST CDS_LIB mstr_standard
J 0
(-2650 4700);
DISPLAY 0.723404 (-2650 4700);
PAINT MONO (-2650 4700);
DISPLAY INVISIBLE (-2650 4700);
FORCEPROP 1 LAST OFFPAGE TRUE
J 0
(-2325 4575);
DISPLAY 0.723404 (-2325 4575);
PAINT GREEN (-2325 4575);
DISPLAY INVISIBLE (-2325 4575);
FORCEPROP 1 LAST COMMENT_BODY TRUE
J 0
(-2695 4605);
DISPLAY 0.872340 (-2695 4605);
PAINT GREEN (-2695 4605);
DISPLAY INVISIBLE (-2695 4605);
FORCEPROP 2 LAST PATH I328
J 0
(-2350 4750);
DISPLAY 0.808511 (-2350 4750);
DISPLAY INVISIBLE (-2350 4750);
FORCEADD GND..1
(-6650 1175);
FORCEPROP 3 LASTPIN (-6650 1225) SIG_NAME GND\g
J 0
(-6640 1235);
DISPLAY 0.659574 (-6640 1235);
PAINT MONO (-6640 1235);
DISPLAY INVISIBLE (-6640 1235);
FORCEPROP 1 LAST VOLTAGE 0.0
J 0
(-6695 1132);
DISPLAY 0.723404 (-6695 1132);
PAINT SKYBLUE (-6695 1132);
DISPLAY INVISIBLE (-6695 1132);
FORCEPROP 1 LAST SIZE 1B
J 0
(-6575 1125);
DISPLAY 0.851064 (-6575 1125);
PAINT GREEN (-6575 1125);
DISPLAY INVISIBLE (-6575 1125);
FORCEPROP 2 LAST CDS_LIB mstr_symbols
J 0
(-6650 1175);
DISPLAY 0.808511 (-6650 1175);
DISPLAY INVISIBLE (-6650 1175);
FORCEPROP 2 LAST BOM_COST MEM
J 0
(-6750 1250);
DISPLAY 0.808511 (-6750 1250);
DISPLAY INVISIBLE (-6750 1250);
FORCEPROP 1 LAST BODY_TYPE PLUMBING
J 0
(-6695 1132);
DISPLAY 0.340426 (-6695 1132);
PAINT GREEN (-6695 1132);
DISPLAY INVISIBLE (-6695 1132);
FORCEPROP 1 LAST HDL_POWER GND
J 0
(-6650 1325);
DISPLAY 0.851064 (-6650 1325);
PAINT GREEN (-6650 1325);
DISPLAY INVISIBLE (-6650 1325);
FORCEPROP 1 LAST PATH I332
J 0
(-6575 1175);
DISPLAY 0.872340 (-6575 1175);
PAINT GREEN (-6575 1175);
DISPLAY INVISIBLE (-6575 1175);
FORCEADD OFFPAGE..5
(-7425 1575);
FORCEPROP 2 LAST $XR0 87 
J 0
(-7649 1575);
DISPLAY 0.638298 (-7649 1575);
PAINT MONO (-7649 1575);
FORCEPROP 2 LAST CDS_LIB mstr_standard
J 0
(-7425 1575);
DISPLAY 0.808511 (-7425 1575);
DISPLAY INVISIBLE (-7425 1575);
FORCEPROP 2 LAST BOM_COST MEM
J 0
(-7500 1650);
DISPLAY 0.808511 (-7500 1650);
DISPLAY INVISIBLE (-7500 1650);
FORCEPROP 1 LAST OFFPAGE TRUE
J 0
(-7100 1450);
DISPLAY 0.872340 (-7100 1450);
PAINT GREEN (-7100 1450);
DISPLAY INVISIBLE (-7100 1450);
FORCEPROP 1 LAST COMMENT_BODY TRUE
J 0
(-7325 1500);
DISPLAY 0.872340 (-7325 1500);
PAINT GREEN (-7325 1500);
DISPLAY INVISIBLE (-7325 1500);
FORCEPROP 2 LAST PATH I333
J 0
(-7375 1650);
DISPLAY 0.808511 (-7375 1650);
DISPLAY INVISIBLE (-7375 1650);
FORCEADD OFFPAGE..1
(-8550 3025);
FORCEPROP 2 LAST $XR0 87 
J 0
(-8771 3025);
DISPLAY 0.638298 (-8771 3025);
PAINT MONO (-8771 3025);
FORCEPROP 2 LAST CDS_LIB mstr_standard
J 0
(-8550 3025);
DISPLAY 0.808511 (-8550 3025);
DISPLAY INVISIBLE (-8550 3025);
FORCEPROP 1 LAST OFFPAGE TRUE
J 0
(-8225 2900);
DISPLAY 0.872340 (-8225 2900);
PAINT GREEN (-8225 2900);
DISPLAY INVISIBLE (-8225 2900);
FORCEPROP 1 LAST COMMENT_BODY TRUE
J 0
(-8425 2925);
DISPLAY 0.872340 (-8425 2925);
PAINT GREEN (-8425 2925);
DISPLAY INVISIBLE (-8425 2925);
FORCEPROP 2 LAST PATH I334
J 0
(-8500 3100);
DISPLAY 0.808511 (-8500 3100);
DISPLAY INVISIBLE (-8500 3100);
FORCEADD Q_RES..2
(-6650 1400);
FORCEPROP 1 LAST LOCATION R761
J 0
(-6605 1525);
DISPLAY 0.489362 (-6605 1525);
PAINT SKYBLUE (-6605 1525);
FORCEPROP 0 LAST $SEC 1
J 0
(-6600 1575);
DISPLAY 0.680851 (-6600 1575);
PAINT MONO (-6600 1575);
DISPLAY INVISIBLE (-6600 1575);
FORCEPROP 0 LAST CDS_SEC 1
J 0
(-6600 1575);
DISPLAY 1.021277 (-6600 1575);
DISPLAY INVISIBLE (-6600 1575);
FORCEPROP 1 LASTPIN (-6650 1500) $PN 1
J 0
(-6645 1462);
DISPLAY 0.489362 (-6645 1462);
PAINT MONO (-6645 1462);
FORCEPROP 1 LASTPIN (-6650 1300) $PN 2
J 0
(-6645 1310);
DISPLAY 0.489362 (-6645 1310);
PAINT MONO (-6645 1310);
FORCEPROP 1 LAST PACK_TYPE 0402LF
J 0
(-6610 1225);
DISPLAY 0.489362 (-6610 1225);
PAINT SKYBLUE (-6610 1225);
FORCEPROP 1 LAST VALUE 15.4K
J 0
(-6605 1475);
DISPLAY 0.489362 (-6605 1475);
PAINT SKYBLUE (-6605 1475);
FORCEPROP 1 LAST TOLERANCE 1%
J 0
(-6605 1425);
DISPLAY 0.489362 (-6605 1425);
PAINT SKYBLUE (-6605 1425);
FORCEPROP 1 LAST MATERIAL CHIP
J 0
(-6610 1325);
DISPLAY 0.489362 (-6610 1325);
PAINT SKYBLUE (-6610 1325);
FORCEPROP 1 LAST WATTAGE 1/16W
J 0
(-6610 1375);
DISPLAY 0.489362 (-6610 1375);
PAINT SKYBLUE (-6610 1375);
FORCEPROP 2 LAST CDS_LIB pure_quanta
J 0
(-6650 1400);
DISPLAY INVISIBLE (-6650 1400);
FORCEPROP 1 LAST PATH I349
J 0
(-6600 1575);
DISPLAY 0.978723 (-6600 1575);
PAINT WHITE (-6600 1575);
DISPLAY INVISIBLE (-6600 1575);
FORCEPROP 1 LAST PART_NUMBER CS31542FB02
J 0
(-6610 1275);
DISPLAY 0.489362 (-6610 1275);
PAINT SKYBLUE (-6610 1275);
DISPLAY INVISIBLE (-6610 1275);
FORCEADD SCONN288_DDR506112002KQ..1
(-7100 3775);
FORCEPROP 1 LAST LOCATION J15
J 0
(-7550 5850);
DISPLAY 0.574468 (-7550 5850);
PAINT SKYBLUE (-7550 5850);
FORCEPROP 0 LAST $SEC 1
J 0
(-7550 6000);
DISPLAY 0.680851 (-7550 6000);
PAINT MONO (-7550 6000);
DISPLAY INVISIBLE (-7550 6000);
FORCEPROP 2 LAST CDS_SEC 1
J 0
(-7550 6000);
DISPLAY 1.021277 (-7550 6000);
DISPLAY INVISIBLE (-7550 6000);
FORCEPROP 0 LASTPIN (-7700 3175) $PN 62
J 2
(-7710 3185);
DISPLAY 0.680851 (-7710 3185);
PAINT MONO (-7710 3185);
FORCEPROP 0 LASTPIN (-7700 5225) $PN 66
J 2
(-7710 5235);
DISPLAY 0.680851 (-7710 5235);
PAINT MONO (-7710 5235);
FORCEPROP 0 LASTPIN (-7700 4825) $PN 76
J 2
(-7710 4835);
DISPLAY 0.680851 (-7710 4835);
PAINT MONO (-7710 4835);
FORCEPROP 0 LASTPIN (-7700 5275) $PN 211
J 2
(-7710 5285);
DISPLAY 0.680851 (-7710 5285);
PAINT MONO (-7710 5285);
FORCEPROP 0 LASTPIN (-7700 4875) $PN 221
J 2
(-7710 4885);
DISPLAY 0.680851 (-7710 4885);
PAINT MONO (-7710 4885);
FORCEPROP 0 LASTPIN (-7700 5325) $PN 68
J 2
(-7710 5335);
DISPLAY 0.680851 (-7710 5335);
PAINT MONO (-7710 5335);
FORCEPROP 0 LASTPIN (-7700 4925) $PN 78
J 2
(-7710 4935);
DISPLAY 0.680851 (-7710 4935);
PAINT MONO (-7710 4935);
FORCEPROP 0 LASTPIN (-7700 5375) $PN 213
J 2
(-7710 5385);
DISPLAY 0.680851 (-7710 5385);
PAINT MONO (-7710 5385);
FORCEPROP 0 LASTPIN (-7700 4975) $PN 223
J 2
(-7710 4985);
DISPLAY 0.680851 (-7710 4985);
PAINT MONO (-7710 4985);
FORCEPROP 0 LASTPIN (-7700 5425) $PN 70
J 2
(-7710 5435);
DISPLAY 0.680851 (-7710 5435);
PAINT MONO (-7710 5435);
FORCEPROP 0 LASTPIN (-7700 5025) $PN 80
J 2
(-7710 5035);
DISPLAY 0.680851 (-7710 5035);
PAINT MONO (-7710 5035);
FORCEPROP 0 LASTPIN (-7700 5475) $PN 215
J 2
(-7710 5485);
DISPLAY 0.680851 (-7710 5485);
PAINT MONO (-7710 5485);
FORCEPROP 0 LASTPIN (-7700 5075) $PN 225
J 2
(-7710 5085);
DISPLAY 0.680851 (-7710 5085);
PAINT MONO (-7710 5085);
FORCEPROP 0 LASTPIN (-7700 5525) $PN 72
J 2
(-7710 5535);
DISPLAY 0.680851 (-7710 5535);
PAINT MONO (-7710 5535);
FORCEPROP 0 LASTPIN (-7700 5125) $PN 82
J 2
(-7710 5135);
DISPLAY 0.680851 (-7710 5135);
PAINT MONO (-7710 5135);
FORCEPROP 0 LASTPIN (-7700 3775) $PN 51
J 2
(-7710 3785);
DISPLAY 0.680851 (-7710 3785);
PAINT MONO (-7710 3785);
FORCEPROP 0 LASTPIN (-7700 3325) $PN 96
J 2
(-7710 3335);
DISPLAY 0.680851 (-7710 3335);
PAINT MONO (-7710 3335);
FORCEPROP 0 LASTPIN (-7700 3825) $PN 53
J 2
(-7710 3835);
DISPLAY 0.680851 (-7710 3835);
PAINT MONO (-7710 3835);
FORCEPROP 0 LASTPIN (-7700 3375) $PN 98
J 2
(-7710 3385);
DISPLAY 0.680851 (-7710 3385);
PAINT MONO (-7710 3385);
FORCEPROP 0 LASTPIN (-7700 3875) $PN 196
J 2
(-7710 3885);
DISPLAY 0.680851 (-7710 3885);
PAINT MONO (-7710 3885);
FORCEPROP 0 LASTPIN (-7700 3425) $PN 241
J 2
(-7710 3435);
DISPLAY 0.680851 (-7710 3435);
PAINT MONO (-7710 3435);
FORCEPROP 0 LASTPIN (-7700 3925) $PN 198
J 2
(-7710 3935);
DISPLAY 0.680851 (-7710 3935);
PAINT MONO (-7710 3935);
FORCEPROP 0 LASTPIN (-7700 3475) $PN 243
J 2
(-7710 3485);
DISPLAY 0.680851 (-7710 3485);
PAINT MONO (-7710 3485);
FORCEPROP 0 LASTPIN (-7700 3975) $PN 58
J 2
(-7710 3985);
DISPLAY 0.680851 (-7710 3985);
PAINT MONO (-7710 3985);
FORCEPROP 0 LASTPIN (-7700 3525) $PN 89
J 2
(-7710 3535);
DISPLAY 0.680851 (-7710 3535);
PAINT MONO (-7710 3535);
FORCEPROP 0 LASTPIN (-7700 4025) $PN 60
J 2
(-7710 4035);
DISPLAY 0.680851 (-7710 4035);
PAINT MONO (-7710 4035);
FORCEPROP 0 LASTPIN (-7700 3575) $PN 91
J 2
(-7710 3585);
DISPLAY 0.680851 (-7710 3585);
PAINT MONO (-7710 3585);
FORCEPROP 0 LASTPIN (-7700 4075) $PN 203
J 2
(-7710 4085);
DISPLAY 0.680851 (-7710 4085);
PAINT MONO (-7710 4085);
FORCEPROP 0 LASTPIN (-7700 3625) $PN 234
J 2
(-7710 3635);
DISPLAY 0.680851 (-7710 3635);
PAINT MONO (-7710 3635);
FORCEPROP 0 LASTPIN (-7700 4125) $PN 205
J 2
(-7710 4135);
DISPLAY 0.680851 (-7710 4135);
PAINT MONO (-7710 4135);
FORCEPROP 0 LASTPIN (-7700 3675) $PN 236
J 2
(-7710 3685);
DISPLAY 0.680851 (-7710 3685);
PAINT MONO (-7710 3685);
FORCEPROP 0 LASTPIN (-7700 4225) $PN 218
J 2
(-7710 4235);
DISPLAY 0.680851 (-7710 4235);
PAINT MONO (-7710 4235);
FORCEPROP 0 LASTPIN (-7700 4275) $PN 217
J 2
(-7710 4285);
DISPLAY 0.680851 (-7710 4285);
PAINT MONO (-7710 4285);
FORCEPROP 0 LASTPIN (-7700 4525) $PN 64
J 2
(-7710 4535);
DISPLAY 0.680851 (-7710 4535);
PAINT MONO (-7710 4535);
FORCEPROP 0 LASTPIN (-7700 4375) $PN 84
J 2
(-7710 4385);
DISPLAY 0.680851 (-7710 4385);
PAINT MONO (-7710 4385);
FORCEPROP 0 LASTPIN (-7700 4575) $PN 209
J 2
(-7710 4585);
DISPLAY 0.680851 (-7710 4585);
PAINT MONO (-7710 4585);
FORCEPROP 0 LASTPIN (-7700 4425) $PN 229
J 2
(-7710 4435);
DISPLAY 0.680851 (-7710 4435);
PAINT MONO (-7710 4435);
FORCEPROP 0 LASTPIN (-6500 3975) $PN 7
J 0
(-6490 3985);
DISPLAY 0.680851 (-6490 3985);
PAINT MONO (-6490 3985);
FORCEPROP 0 LASTPIN (-6500 2325) $PN 100
J 0
(-6490 2335);
DISPLAY 0.680851 (-6490 2335);
PAINT MONO (-6490 2335);
FORCEPROP 0 LASTPIN (-6500 4025) $PN 9
J 0
(-6490 4035);
DISPLAY 0.680851 (-6490 4035);
PAINT MONO (-6490 4035);
FORCEPROP 0 LASTPIN (-6500 2375) $PN 102
J 0
(-6490 2385);
DISPLAY 0.680851 (-6490 2385);
PAINT MONO (-6490 2385);
FORCEPROP 0 LASTPIN (-6500 4075) $PN 152
J 0
(-6490 4085);
DISPLAY 0.680851 (-6490 4085);
PAINT MONO (-6490 4085);
FORCEPROP 0 LASTPIN (-6500 2425) $PN 245
J 0
(-6490 2435);
DISPLAY 0.680851 (-6490 2435);
PAINT MONO (-6490 2435);
FORCEPROP 0 LASTPIN (-6500 4125) $PN 154
J 0
(-6490 4135);
DISPLAY 0.680851 (-6490 4135);
PAINT MONO (-6490 4135);
FORCEPROP 0 LASTPIN (-6500 2475) $PN 247
J 0
(-6490 2485);
DISPLAY 0.680851 (-6490 2485);
PAINT MONO (-6490 2485);
FORCEPROP 0 LASTPIN (-6500 4175) $PN 14
J 0
(-6490 4185);
DISPLAY 0.680851 (-6490 4185);
PAINT MONO (-6490 4185);
FORCEPROP 0 LASTPIN (-6500 2525) $PN 107
J 0
(-6490 2535);
DISPLAY 0.680851 (-6490 2535);
PAINT MONO (-6490 2535);
FORCEPROP 0 LASTPIN (-6500 4225) $PN 16
J 0
(-6490 4235);
DISPLAY 0.680851 (-6490 4235);
PAINT MONO (-6490 4235);
FORCEPROP 0 LASTPIN (-6500 2575) $PN 109
J 0
(-6490 2585);
DISPLAY 0.680851 (-6490 2585);
PAINT MONO (-6490 2585);
FORCEPROP 0 LASTPIN (-6500 4275) $PN 159
J 0
(-6490 4285);
DISPLAY 0.680851 (-6490 4285);
PAINT MONO (-6490 4285);
FORCEPROP 0 LASTPIN (-6500 2625) $PN 252
J 0
(-6490 2635);
DISPLAY 0.680851 (-6490 2635);
PAINT MONO (-6490 2635);
FORCEPROP 0 LASTPIN (-6500 4325) $PN 161
J 0
(-6490 4335);
DISPLAY 0.680851 (-6490 4335);
PAINT MONO (-6490 4335);
FORCEPROP 0 LASTPIN (-6500 2675) $PN 254
J 0
(-6490 2685);
DISPLAY 0.680851 (-6490 2685);
PAINT MONO (-6490 2685);
FORCEPROP 0 LASTPIN (-6500 4375) $PN 18
J 0
(-6490 4385);
DISPLAY 0.680851 (-6490 4385);
PAINT MONO (-6490 4385);
FORCEPROP 0 LASTPIN (-6500 2725) $PN 111
J 0
(-6490 2735);
DISPLAY 0.680851 (-6490 2735);
PAINT MONO (-6490 2735);
FORCEPROP 0 LASTPIN (-6500 4425) $PN 20
J 0
(-6490 4435);
DISPLAY 0.680851 (-6490 4435);
PAINT MONO (-6490 4435);
FORCEPROP 0 LASTPIN (-6500 2775) $PN 113
J 0
(-6490 2785);
DISPLAY 0.680851 (-6490 2785);
PAINT MONO (-6490 2785);
FORCEPROP 0 LASTPIN (-6500 4475) $PN 163
J 0
(-6490 4485);
DISPLAY 0.680851 (-6490 4485);
PAINT MONO (-6490 4485);
FORCEPROP 0 LASTPIN (-6500 2825) $PN 256
J 0
(-6490 2835);
DISPLAY 0.680851 (-6490 2835);
PAINT MONO (-6490 2835);
FORCEPROP 0 LASTPIN (-6500 4525) $PN 165
J 0
(-6490 4535);
DISPLAY 0.680851 (-6490 4535);
PAINT MONO (-6490 4535);
FORCEPROP 0 LASTPIN (-6500 2875) $PN 258
J 0
(-6490 2885);
DISPLAY 0.680851 (-6490 2885);
PAINT MONO (-6490 2885);
FORCEPROP 0 LASTPIN (-6500 4575) $PN 25
J 0
(-6490 4585);
DISPLAY 0.680851 (-6490 4585);
PAINT MONO (-6490 4585);
FORCEPROP 0 LASTPIN (-6500 2925) $PN 118
J 0
(-6490 2935);
DISPLAY 0.680851 (-6490 2935);
PAINT MONO (-6490 2935);
FORCEPROP 0 LASTPIN (-6500 4625) $PN 27
J 0
(-6490 4635);
DISPLAY 0.680851 (-6490 4635);
PAINT MONO (-6490 4635);
FORCEPROP 0 LASTPIN (-6500 2975) $PN 120
J 0
(-6490 2985);
DISPLAY 0.680851 (-6490 2985);
PAINT MONO (-6490 2985);
FORCEPROP 0 LASTPIN (-6500 4675) $PN 170
J 0
(-6490 4685);
DISPLAY 0.680851 (-6490 4685);
PAINT MONO (-6490 4685);
FORCEPROP 0 LASTPIN (-6500 3025) $PN 263
J 0
(-6490 3035);
DISPLAY 0.680851 (-6490 3035);
PAINT MONO (-6490 3035);
FORCEPROP 0 LASTPIN (-6500 4725) $PN 172
J 0
(-6490 4735);
DISPLAY 0.680851 (-6490 4735);
PAINT MONO (-6490 4735);
FORCEPROP 0 LASTPIN (-6500 3075) $PN 265
J 0
(-6490 3085);
DISPLAY 0.680851 (-6490 3085);
PAINT MONO (-6490 3085);
FORCEPROP 0 LASTPIN (-6500 4775) $PN 29
J 0
(-6490 4785);
DISPLAY 0.680851 (-6490 4785);
PAINT MONO (-6490 4785);
FORCEPROP 0 LASTPIN (-6500 3125) $PN 122
J 0
(-6490 3135);
DISPLAY 0.680851 (-6490 3135);
PAINT MONO (-6490 3135);
FORCEPROP 0 LASTPIN (-6500 4825) $PN 31
J 0
(-6490 4835);
DISPLAY 0.680851 (-6490 4835);
PAINT MONO (-6490 4835);
FORCEPROP 0 LASTPIN (-6500 3175) $PN 124
J 0
(-6490 3185);
DISPLAY 0.680851 (-6490 3185);
PAINT MONO (-6490 3185);
FORCEPROP 0 LASTPIN (-6500 4875) $PN 174
J 0
(-6490 4885);
DISPLAY 0.680851 (-6490 4885);
PAINT MONO (-6490 4885);
FORCEPROP 0 LASTPIN (-6500 3225) $PN 267
J 0
(-6490 3235);
DISPLAY 0.680851 (-6490 3235);
PAINT MONO (-6490 3235);
FORCEPROP 0 LASTPIN (-6500 4925) $PN 176
J 0
(-6490 4935);
DISPLAY 0.680851 (-6490 4935);
PAINT MONO (-6490 4935);
FORCEPROP 0 LASTPIN (-6500 3275) $PN 269
J 0
(-6490 3285);
DISPLAY 0.680851 (-6490 3285);
PAINT MONO (-6490 3285);
FORCEPROP 0 LASTPIN (-6500 4975) $PN 36
J 0
(-6490 4985);
DISPLAY 0.680851 (-6490 4985);
PAINT MONO (-6490 4985);
FORCEPROP 0 LASTPIN (-6500 3325) $PN 129
J 0
(-6490 3335);
DISPLAY 0.680851 (-6490 3335);
PAINT MONO (-6490 3335);
FORCEPROP 0 LASTPIN (-6500 5025) $PN 38
J 0
(-6490 5035);
DISPLAY 0.680851 (-6490 5035);
PAINT MONO (-6490 5035);
FORCEPROP 0 LASTPIN (-6500 3375) $PN 131
J 0
(-6490 3385);
DISPLAY 0.680851 (-6490 3385);
PAINT MONO (-6490 3385);
FORCEPROP 0 LASTPIN (-6500 5075) $PN 181
J 0
(-6490 5085);
DISPLAY 0.680851 (-6490 5085);
PAINT MONO (-6490 5085);
FORCEPROP 0 LASTPIN (-6500 3425) $PN 274
J 0
(-6490 3435);
DISPLAY 0.680851 (-6490 3435);
PAINT MONO (-6490 3435);
FORCEPROP 0 LASTPIN (-6500 5125) $PN 183
J 0
(-6490 5135);
DISPLAY 0.680851 (-6490 5135);
PAINT MONO (-6490 5135);
FORCEPROP 0 LASTPIN (-6500 3475) $PN 276
J 0
(-6490 3485);
DISPLAY 0.680851 (-6490 3485);
PAINT MONO (-6490 3485);
FORCEPROP 0 LASTPIN (-6500 5175) $PN 40
J 0
(-6490 5185);
DISPLAY 0.680851 (-6490 5185);
PAINT MONO (-6490 5185);
FORCEPROP 0 LASTPIN (-6500 3525) $PN 133
J 0
(-6490 3535);
DISPLAY 0.680851 (-6490 3535);
PAINT MONO (-6490 3535);
FORCEPROP 0 LASTPIN (-6500 5225) $PN 42
J 0
(-6490 5235);
DISPLAY 0.680851 (-6490 5235);
PAINT MONO (-6490 5235);
FORCEPROP 0 LASTPIN (-6500 3575) $PN 135
J 0
(-6490 3585);
DISPLAY 0.680851 (-6490 3585);
PAINT MONO (-6490 3585);
FORCEPROP 0 LASTPIN (-6500 5275) $PN 185
J 0
(-6490 5285);
DISPLAY 0.680851 (-6490 5285);
PAINT MONO (-6490 5285);
FORCEPROP 0 LASTPIN (-6500 3625) $PN 278
J 0
(-6490 3635);
DISPLAY 0.680851 (-6490 3635);
PAINT MONO (-6490 3635);
FORCEPROP 0 LASTPIN (-6500 5325) $PN 187
J 0
(-6490 5335);
DISPLAY 0.680851 (-6490 5335);
PAINT MONO (-6490 5335);
FORCEPROP 0 LASTPIN (-6500 3675) $PN 280
J 0
(-6490 3685);
DISPLAY 0.680851 (-6490 3685);
PAINT MONO (-6490 3685);
FORCEPROP 0 LASTPIN (-6500 5375) $PN 47
J 0
(-6490 5385);
DISPLAY 0.680851 (-6490 5385);
PAINT MONO (-6490 5385);
FORCEPROP 0 LASTPIN (-6500 3725) $PN 140
J 0
(-6490 3735);
DISPLAY 0.680851 (-6490 3735);
PAINT MONO (-6490 3735);
FORCEPROP 0 LASTPIN (-6500 5425) $PN 49
J 0
(-6490 5435);
DISPLAY 0.680851 (-6490 5435);
PAINT MONO (-6490 5435);
FORCEPROP 0 LASTPIN (-6500 3775) $PN 142
J 0
(-6490 3785);
DISPLAY 0.680851 (-6490 3785);
PAINT MONO (-6490 3785);
FORCEPROP 0 LASTPIN (-6500 5475) $PN 192
J 0
(-6490 5485);
DISPLAY 0.680851 (-6490 5485);
PAINT MONO (-6490 5485);
FORCEPROP 0 LASTPIN (-6500 3825) $PN 285
J 0
(-6490 3835);
DISPLAY 0.680851 (-6490 3835);
PAINT MONO (-6490 3835);
FORCEPROP 0 LASTPIN (-6500 5525) $PN 194
J 0
(-6490 5535);
DISPLAY 0.680851 (-6490 5535);
PAINT MONO (-6490 5535);
FORCEPROP 0 LASTPIN (-6500 3875) $PN 287
J 0
(-6490 3885);
DISPLAY 0.680851 (-6490 3885);
PAINT MONO (-6490 3885);
FORCEPROP 0 LASTPIN (-7700 3025) $PN 148
J 2
(-7710 3035);
DISPLAY 0.680851 (-7710 3035);
PAINT MONO (-7710 3035);
FORCEPROP 0 LASTPIN (-7700 2925) $PN 4
J 2
(-7710 2935);
DISPLAY 0.680851 (-7710 2935);
PAINT MONO (-7710 2935);
FORCEPROP 0 LASTPIN (-7700 2975) $PN 5
J 2
(-7710 2985);
DISPLAY 0.680851 (-7710 2985);
PAINT MONO (-7710 2985);
FORCEPROP 0 LASTPIN (-7700 2125) $PN 86
J 2
(-7710 2135);
DISPLAY 0.680851 (-7710 2135);
PAINT MONO (-7710 2135);
FORCEPROP 0 LASTPIN (-7700 2075) $PN 87
J 2
(-7710 2085);
DISPLAY 0.680851 (-7710 2085);
PAINT MONO (-7710 2085);
FORCEPROP 0 LASTPIN (-7700 4725) $PN 74
J 2
(-7710 4735);
DISPLAY 0.680851 (-7710 4735);
PAINT MONO (-7710 4735);
FORCEPROP 0 LASTPIN (-7700 4675) $PN 227
J 2
(-7710 4685);
DISPLAY 0.680851 (-7710 4685);
PAINT MONO (-7710 4685);
FORCEPROP 0 LASTPIN (-7700 2675) $PN 147
J 2
(-7710 2685);
DISPLAY 0.680851 (-7710 2685);
PAINT MONO (-7710 2685);
FORCEPROP 0 LASTPIN (-7700 3225) $PN 207
J 2
(-7710 3235);
DISPLAY 0.680851 (-7710 3235);
PAINT MONO (-7710 3235);
FORCEPROP 0 LASTPIN (-7700 2275) $PN 2
J 2
(-7710 2285);
DISPLAY 0.680851 (-7710 2285);
PAINT MONO (-7710 2285);
FORCEPROP 0 LASTPIN (-7700 2325) $PN 144
J 2
(-7710 2335);
DISPLAY 0.680851 (-7710 2335);
PAINT MONO (-7710 2335);
FORCEPROP 0 LASTPIN (-7700 2375) $PN 149
J 2
(-7710 2385);
DISPLAY 0.680851 (-7710 2385);
PAINT MONO (-7710 2385);
FORCEPROP 0 LASTPIN (-7700 2425) $PN 150
J 2
(-7710 2435);
DISPLAY 0.680851 (-7710 2435);
PAINT MONO (-7710 2435);
FORCEPROP 0 LASTPIN (-7700 2475) $PN 220
J 2
(-7710 2485);
DISPLAY 0.680851 (-7710 2485);
PAINT MONO (-7710 2485);
FORCEPROP 0 LASTPIN (-7700 2525) $PN 231
J 2
(-7710 2535);
DISPLAY 0.680851 (-7710 2535);
PAINT MONO (-7710 2535);
FORCEPROP 0 LASTPIN (-7700 2575) $PN 232
J 2
(-7710 2585);
DISPLAY 0.680851 (-7710 2585);
PAINT MONO (-7710 2585);
FORCEPROP 0 LASTPIN (-7700 3075) $PN 3
J 2
(-7710 3085);
DISPLAY 0.680851 (-7710 3085);
PAINT MONO (-7710 3085);
FORCEPROP 1 LAST MATERIAL IO
J 0
(-7550 5700);
DISPLAY 0.468085 (-7550 5700);
PAINT SKYBLUE (-7550 5700);
FORCEPROP 2 LAST VALUE SCONN288_DDR506112002KQ
J 0
(-7550 5900);
DISPLAY 0.489362 (-7550 5900);
PAINT SKYBLUE (-7550 5900);
FORCEPROP 2 LAST PART_TYPE SMLF
J 0
(-7550 5950);
DISPLAY 1.021277 (-7550 5950);
FORCEPROP 2 LAST CDS_LIB pure_quanta
J 0
(-7100 3775);
DISPLAY INVISIBLE (-7100 3775);
FORCEPROP 1 LAST NEEDS_NO_SIZE TRUE
J 0
(-7100 3775);
DISPLAY 0.723404 (-7100 3775);
PAINT GREEN (-7100 3775);
DISPLAY INVISIBLE (-7100 3775);
FORCEPROP 1 LAST CDS_LMAN_SYM_OUTLINE -450,1900,450,-1850
J 0
(-7100 3775);
DISPLAY 0.468085 (-7100 3775);
PAINT GREEN (-7100 3775);
DISPLAY INVISIBLE (-7100 3775);
FORCEPROP 1 LAST PATH I350
J 0
(-7100 3775);
DISPLAY 0.723404 (-7100 3775);
PAINT GREEN (-7100 3775);
DISPLAY INVISIBLE (-7100 3775);
FORCEPROP 1 LAST PART_NUMBER DFHST8FS479
J 0
(-7550 5775);
DISPLAY 0.468085 (-7550 5775);
PAINT SKYBLUE (-7550 5775);
DISPLAY INVISIBLE (-7550 5775);
FORCEADD SCONN288_DDR506112002KQ..3
(-1225 3575);
FORCEPROP 1 LAST LOCATION J15
J 0
(-1675 5550);
DISPLAY 0.574468 (-1675 5550);
PAINT SKYBLUE (-1675 5550);
FORCEPROP 0 LAST $SEC 3
J 0
(-1675 5700);
DISPLAY 0.680851 (-1675 5700);
PAINT MONO (-1675 5700);
DISPLAY INVISIBLE (-1675 5700);
FORCEPROP 2 LAST CDS_SEC 3
J 0
(-1675 5700);
DISPLAY 1.021277 (-1675 5700);
DISPLAY INVISIBLE (-1675 5700);
FORCEPROP 0 LASTPIN (-625 1975) $PN G1
J 0
(-615 1985);
DISPLAY 0.680851 (-615 1985);
PAINT MONO (-615 1985);
FORCEPROP 0 LASTPIN (-625 1925) $PN G2
J 0
(-615 1935);
DISPLAY 0.680851 (-615 1935);
PAINT MONO (-615 1935);
FORCEPROP 0 LASTPIN (-625 1875) $PN G3
J 0
(-615 1885);
DISPLAY 0.680851 (-615 1885);
PAINT MONO (-615 1885);
FORCEPROP 0 LASTPIN (-1825 5125) $PN 1
J 2
(-1835 5135);
DISPLAY 0.680851 (-1835 5135);
PAINT MONO (-1835 5135);
FORCEPROP 0 LASTPIN (-1825 5175) $PN 145
J 2
(-1835 5185);
DISPLAY 0.680851 (-1835 5185);
PAINT MONO (-1835 5185);
FORCEPROP 0 LASTPIN (-1825 5225) $PN 146
J 2
(-1835 5235);
DISPLAY 0.680851 (-1835 5235);
PAINT MONO (-1835 5235);
FORCEPROP 0 LASTPIN (-625 2075) $PN 6
J 0
(-615 2085);
DISPLAY 0.680851 (-615 2085);
PAINT MONO (-615 2085);
FORCEPROP 0 LASTPIN (-625 2125) $PN 8
J 0
(-615 2135);
DISPLAY 0.680851 (-615 2135);
PAINT MONO (-615 2135);
FORCEPROP 0 LASTPIN (-625 2175) $PN 10
J 0
(-615 2185);
DISPLAY 0.680851 (-615 2185);
PAINT MONO (-615 2185);
FORCEPROP 0 LASTPIN (-625 2225) $PN 13
J 0
(-615 2235);
DISPLAY 0.680851 (-615 2235);
PAINT MONO (-615 2235);
FORCEPROP 0 LASTPIN (-625 2275) $PN 15
J 0
(-615 2285);
DISPLAY 0.680851 (-615 2285);
PAINT MONO (-615 2285);
FORCEPROP 0 LASTPIN (-625 2325) $PN 17
J 0
(-615 2335);
DISPLAY 0.680851 (-615 2335);
PAINT MONO (-615 2335);
FORCEPROP 0 LASTPIN (-625 2375) $PN 19
J 0
(-615 2385);
DISPLAY 0.680851 (-615 2385);
PAINT MONO (-615 2385);
FORCEPROP 0 LASTPIN (-625 2425) $PN 21
J 0
(-615 2435);
DISPLAY 0.680851 (-615 2435);
PAINT MONO (-615 2435);
FORCEPROP 0 LASTPIN (-625 2475) $PN 24
J 0
(-615 2485);
DISPLAY 0.680851 (-615 2485);
PAINT MONO (-615 2485);
FORCEPROP 0 LASTPIN (-625 2525) $PN 26
J 0
(-615 2535);
DISPLAY 0.680851 (-615 2535);
PAINT MONO (-615 2535);
FORCEPROP 0 LASTPIN (-625 2575) $PN 28
J 0
(-615 2585);
DISPLAY 0.680851 (-615 2585);
PAINT MONO (-615 2585);
FORCEPROP 0 LASTPIN (-625 2625) $PN 30
J 0
(-615 2635);
DISPLAY 0.680851 (-615 2635);
PAINT MONO (-615 2635);
FORCEPROP 0 LASTPIN (-625 2675) $PN 32
J 0
(-615 2685);
DISPLAY 0.680851 (-615 2685);
PAINT MONO (-615 2685);
FORCEPROP 0 LASTPIN (-625 2725) $PN 35
J 0
(-615 2735);
DISPLAY 0.680851 (-615 2735);
PAINT MONO (-615 2735);
FORCEPROP 0 LASTPIN (-625 2775) $PN 37
J 0
(-615 2785);
DISPLAY 0.680851 (-615 2785);
PAINT MONO (-615 2785);
FORCEPROP 0 LASTPIN (-625 2825) $PN 39
J 0
(-615 2835);
DISPLAY 0.680851 (-615 2835);
PAINT MONO (-615 2835);
FORCEPROP 0 LASTPIN (-625 2875) $PN 41
J 0
(-615 2885);
DISPLAY 0.680851 (-615 2885);
PAINT MONO (-615 2885);
FORCEPROP 0 LASTPIN (-625 2925) $PN 43
J 0
(-615 2935);
DISPLAY 0.680851 (-615 2935);
PAINT MONO (-615 2935);
FORCEPROP 0 LASTPIN (-625 2975) $PN 46
J 0
(-615 2985);
DISPLAY 0.680851 (-615 2985);
PAINT MONO (-615 2985);
FORCEPROP 0 LASTPIN (-625 3025) $PN 48
J 0
(-615 3035);
DISPLAY 0.680851 (-615 3035);
PAINT MONO (-615 3035);
FORCEPROP 0 LASTPIN (-625 3075) $PN 50
J 0
(-615 3085);
DISPLAY 0.680851 (-615 3085);
PAINT MONO (-615 3085);
FORCEPROP 0 LASTPIN (-625 3125) $PN 52
J 0
(-615 3135);
DISPLAY 0.680851 (-615 3135);
PAINT MONO (-615 3135);
FORCEPROP 0 LASTPIN (-625 3175) $PN 54
J 0
(-615 3185);
DISPLAY 0.680851 (-615 3185);
PAINT MONO (-615 3185);
FORCEPROP 0 LASTPIN (-625 3225) $PN 57
J 0
(-615 3235);
DISPLAY 0.680851 (-615 3235);
PAINT MONO (-615 3235);
FORCEPROP 0 LASTPIN (-625 3275) $PN 59
J 0
(-615 3285);
DISPLAY 0.680851 (-615 3285);
PAINT MONO (-615 3285);
FORCEPROP 0 LASTPIN (-625 3325) $PN 61
J 0
(-615 3335);
DISPLAY 0.680851 (-615 3335);
PAINT MONO (-615 3335);
FORCEPROP 0 LASTPIN (-625 3375) $PN 63
J 0
(-615 3385);
DISPLAY 0.680851 (-615 3385);
PAINT MONO (-615 3385);
FORCEPROP 0 LASTPIN (-625 3425) $PN 65
J 0
(-615 3435);
DISPLAY 0.680851 (-615 3435);
PAINT MONO (-615 3435);
FORCEPROP 0 LASTPIN (-625 3475) $PN 67
J 0
(-615 3485);
DISPLAY 0.680851 (-615 3485);
PAINT MONO (-615 3485);
FORCEPROP 0 LASTPIN (-625 3525) $PN 69
J 0
(-615 3535);
DISPLAY 0.680851 (-615 3535);
PAINT MONO (-615 3535);
FORCEPROP 0 LASTPIN (-625 3575) $PN 71
J 0
(-615 3585);
DISPLAY 0.680851 (-615 3585);
PAINT MONO (-615 3585);
FORCEPROP 0 LASTPIN (-625 3625) $PN 73
J 0
(-615 3635);
DISPLAY 0.680851 (-615 3635);
PAINT MONO (-615 3635);
FORCEPROP 0 LASTPIN (-625 3675) $PN 75
J 0
(-615 3685);
DISPLAY 0.680851 (-615 3685);
PAINT MONO (-615 3685);
FORCEPROP 0 LASTPIN (-625 3725) $PN 77
J 0
(-615 3735);
DISPLAY 0.680851 (-615 3735);
PAINT MONO (-615 3735);
FORCEPROP 0 LASTPIN (-625 3775) $PN 79
J 0
(-615 3785);
DISPLAY 0.680851 (-615 3785);
PAINT MONO (-615 3785);
FORCEPROP 0 LASTPIN (-625 3825) $PN 81
J 0
(-615 3835);
DISPLAY 0.680851 (-615 3835);
PAINT MONO (-615 3835);
FORCEPROP 0 LASTPIN (-625 3875) $PN 83
J 0
(-615 3885);
DISPLAY 0.680851 (-615 3885);
PAINT MONO (-615 3885);
FORCEPROP 0 LASTPIN (-625 3925) $PN 85
J 0
(-615 3935);
DISPLAY 0.680851 (-615 3935);
PAINT MONO (-615 3935);
FORCEPROP 0 LASTPIN (-625 3975) $PN 88
J 0
(-615 3985);
DISPLAY 0.680851 (-615 3985);
PAINT MONO (-615 3985);
FORCEPROP 0 LASTPIN (-625 4025) $PN 90
J 0
(-615 4035);
DISPLAY 0.680851 (-615 4035);
PAINT MONO (-615 4035);
FORCEPROP 0 LASTPIN (-625 4075) $PN 92
J 0
(-615 4085);
DISPLAY 0.680851 (-615 4085);
PAINT MONO (-615 4085);
FORCEPROP 0 LASTPIN (-625 4125) $PN 95
J 0
(-615 4135);
DISPLAY 0.680851 (-615 4135);
PAINT MONO (-615 4135);
FORCEPROP 0 LASTPIN (-625 4175) $PN 97
J 0
(-615 4185);
DISPLAY 0.680851 (-615 4185);
PAINT MONO (-615 4185);
FORCEPROP 0 LASTPIN (-625 4225) $PN 99
J 0
(-615 4235);
DISPLAY 0.680851 (-615 4235);
PAINT MONO (-615 4235);
FORCEPROP 0 LASTPIN (-625 4275) $PN 101
J 0
(-615 4285);
DISPLAY 0.680851 (-615 4285);
PAINT MONO (-615 4285);
FORCEPROP 0 LASTPIN (-625 4325) $PN 103
J 0
(-615 4335);
DISPLAY 0.680851 (-615 4335);
PAINT MONO (-615 4335);
FORCEPROP 0 LASTPIN (-625 4375) $PN 106
J 0
(-615 4385);
DISPLAY 0.680851 (-615 4385);
PAINT MONO (-615 4385);
FORCEPROP 0 LASTPIN (-625 4425) $PN 108
J 0
(-615 4435);
DISPLAY 0.680851 (-615 4435);
PAINT MONO (-615 4435);
FORCEPROP 0 LASTPIN (-625 4475) $PN 110
J 0
(-615 4485);
DISPLAY 0.680851 (-615 4485);
PAINT MONO (-615 4485);
FORCEPROP 0 LASTPIN (-625 4525) $PN 112
J 0
(-615 4535);
DISPLAY 0.680851 (-615 4535);
PAINT MONO (-615 4535);
FORCEPROP 0 LASTPIN (-625 4575) $PN 114
J 0
(-615 4585);
DISPLAY 0.680851 (-615 4585);
PAINT MONO (-615 4585);
FORCEPROP 0 LASTPIN (-625 4625) $PN 117
J 0
(-615 4635);
DISPLAY 0.680851 (-615 4635);
PAINT MONO (-615 4635);
FORCEPROP 0 LASTPIN (-625 4675) $PN 119
J 0
(-615 4685);
DISPLAY 0.680851 (-615 4685);
PAINT MONO (-615 4685);
FORCEPROP 0 LASTPIN (-625 4725) $PN 121
J 0
(-615 4735);
DISPLAY 0.680851 (-615 4735);
PAINT MONO (-615 4735);
FORCEPROP 0 LASTPIN (-625 4775) $PN 123
J 0
(-615 4785);
DISPLAY 0.680851 (-615 4785);
PAINT MONO (-615 4785);
FORCEPROP 0 LASTPIN (-625 4825) $PN 125
J 0
(-615 4835);
DISPLAY 0.680851 (-615 4835);
PAINT MONO (-615 4835);
FORCEPROP 0 LASTPIN (-625 4875) $PN 128
J 0
(-615 4885);
DISPLAY 0.680851 (-615 4885);
PAINT MONO (-615 4885);
FORCEPROP 0 LASTPIN (-625 4925) $PN 130
J 0
(-615 4935);
DISPLAY 0.680851 (-615 4935);
PAINT MONO (-615 4935);
FORCEPROP 0 LASTPIN (-625 4975) $PN 132
J 0
(-615 4985);
DISPLAY 0.680851 (-615 4985);
PAINT MONO (-615 4985);
FORCEPROP 0 LASTPIN (-625 5025) $PN 134
J 0
(-615 5035);
DISPLAY 0.680851 (-615 5035);
PAINT MONO (-615 5035);
FORCEPROP 0 LASTPIN (-625 5075) $PN 136
J 0
(-615 5085);
DISPLAY 0.680851 (-615 5085);
PAINT MONO (-615 5085);
FORCEPROP 0 LASTPIN (-625 5125) $PN 139
J 0
(-615 5135);
DISPLAY 0.680851 (-615 5135);
PAINT MONO (-615 5135);
FORCEPROP 0 LASTPIN (-625 5175) $PN 141
J 0
(-615 5185);
DISPLAY 0.680851 (-615 5185);
PAINT MONO (-615 5185);
FORCEPROP 0 LASTPIN (-625 5225) $PN 143
J 0
(-615 5235);
DISPLAY 0.680851 (-615 5235);
PAINT MONO (-615 5235);
FORCEPROP 0 LASTPIN (-1825 1975) $PN 151
J 2
(-1835 1985);
DISPLAY 0.680851 (-1835 1985);
PAINT MONO (-1835 1985);
FORCEPROP 0 LASTPIN (-1825 2025) $PN 153
J 2
(-1835 2035);
DISPLAY 0.680851 (-1835 2035);
PAINT MONO (-1835 2035);
FORCEPROP 0 LASTPIN (-1825 2075) $PN 155
J 2
(-1835 2085);
DISPLAY 0.680851 (-1835 2085);
PAINT MONO (-1835 2085);
FORCEPROP 0 LASTPIN (-1825 2125) $PN 158
J 2
(-1835 2135);
DISPLAY 0.680851 (-1835 2135);
PAINT MONO (-1835 2135);
FORCEPROP 0 LASTPIN (-1825 2175) $PN 160
J 2
(-1835 2185);
DISPLAY 0.680851 (-1835 2185);
PAINT MONO (-1835 2185);
FORCEPROP 0 LASTPIN (-1825 2225) $PN 162
J 2
(-1835 2235);
DISPLAY 0.680851 (-1835 2235);
PAINT MONO (-1835 2235);
FORCEPROP 0 LASTPIN (-1825 2275) $PN 164
J 2
(-1835 2285);
DISPLAY 0.680851 (-1835 2285);
PAINT MONO (-1835 2285);
FORCEPROP 0 LASTPIN (-1825 2325) $PN 166
J 2
(-1835 2335);
DISPLAY 0.680851 (-1835 2335);
PAINT MONO (-1835 2335);
FORCEPROP 0 LASTPIN (-1825 2375) $PN 169
J 2
(-1835 2385);
DISPLAY 0.680851 (-1835 2385);
PAINT MONO (-1835 2385);
FORCEPROP 0 LASTPIN (-1825 2425) $PN 171
J 2
(-1835 2435);
DISPLAY 0.680851 (-1835 2435);
PAINT MONO (-1835 2435);
FORCEPROP 0 LASTPIN (-1825 2475) $PN 173
J 2
(-1835 2485);
DISPLAY 0.680851 (-1835 2485);
PAINT MONO (-1835 2485);
FORCEPROP 0 LASTPIN (-1825 2525) $PN 175
J 2
(-1835 2535);
DISPLAY 0.680851 (-1835 2535);
PAINT MONO (-1835 2535);
FORCEPROP 0 LASTPIN (-1825 2575) $PN 177
J 2
(-1835 2585);
DISPLAY 0.680851 (-1835 2585);
PAINT MONO (-1835 2585);
FORCEPROP 0 LASTPIN (-1825 2625) $PN 180
J 2
(-1835 2635);
DISPLAY 0.680851 (-1835 2635);
PAINT MONO (-1835 2635);
FORCEPROP 0 LASTPIN (-1825 2675) $PN 182
J 2
(-1835 2685);
DISPLAY 0.680851 (-1835 2685);
PAINT MONO (-1835 2685);
FORCEPROP 0 LASTPIN (-1825 2725) $PN 184
J 2
(-1835 2735);
DISPLAY 0.680851 (-1835 2735);
PAINT MONO (-1835 2735);
FORCEPROP 0 LASTPIN (-1825 2775) $PN 186
J 2
(-1835 2785);
DISPLAY 0.680851 (-1835 2785);
PAINT MONO (-1835 2785);
FORCEPROP 0 LASTPIN (-1825 2825) $PN 188
J 2
(-1835 2835);
DISPLAY 0.680851 (-1835 2835);
PAINT MONO (-1835 2835);
FORCEPROP 0 LASTPIN (-1825 2875) $PN 191
J 2
(-1835 2885);
DISPLAY 0.680851 (-1835 2885);
PAINT MONO (-1835 2885);
FORCEPROP 0 LASTPIN (-1825 2925) $PN 193
J 2
(-1835 2935);
DISPLAY 0.680851 (-1835 2935);
PAINT MONO (-1835 2935);
FORCEPROP 0 LASTPIN (-1825 2975) $PN 195
J 2
(-1835 2985);
DISPLAY 0.680851 (-1835 2985);
PAINT MONO (-1835 2985);
FORCEPROP 0 LASTPIN (-1825 3025) $PN 197
J 2
(-1835 3035);
DISPLAY 0.680851 (-1835 3035);
PAINT MONO (-1835 3035);
FORCEPROP 0 LASTPIN (-1825 3075) $PN 199
J 2
(-1835 3085);
DISPLAY 0.680851 (-1835 3085);
PAINT MONO (-1835 3085);
FORCEPROP 0 LASTPIN (-1825 3125) $PN 202
J 2
(-1835 3135);
DISPLAY 0.680851 (-1835 3135);
PAINT MONO (-1835 3135);
FORCEPROP 0 LASTPIN (-1825 3175) $PN 204
J 2
(-1835 3185);
DISPLAY 0.680851 (-1835 3185);
PAINT MONO (-1835 3185);
FORCEPROP 0 LASTPIN (-1825 3225) $PN 206
J 2
(-1835 3235);
DISPLAY 0.680851 (-1835 3235);
PAINT MONO (-1835 3235);
FORCEPROP 0 LASTPIN (-1825 3275) $PN 208
J 2
(-1835 3285);
DISPLAY 0.680851 (-1835 3285);
PAINT MONO (-1835 3285);
FORCEPROP 0 LASTPIN (-1825 3325) $PN 210
J 2
(-1835 3335);
DISPLAY 0.680851 (-1835 3335);
PAINT MONO (-1835 3335);
FORCEPROP 0 LASTPIN (-1825 3375) $PN 212
J 2
(-1835 3385);
DISPLAY 0.680851 (-1835 3385);
PAINT MONO (-1835 3385);
FORCEPROP 0 LASTPIN (-1825 3425) $PN 214
J 2
(-1835 3435);
DISPLAY 0.680851 (-1835 3435);
PAINT MONO (-1835 3435);
FORCEPROP 0 LASTPIN (-1825 3475) $PN 216
J 2
(-1835 3485);
DISPLAY 0.680851 (-1835 3485);
PAINT MONO (-1835 3485);
FORCEPROP 0 LASTPIN (-1825 3525) $PN 219
J 2
(-1835 3535);
DISPLAY 0.680851 (-1835 3535);
PAINT MONO (-1835 3535);
FORCEPROP 0 LASTPIN (-1825 3575) $PN 222
J 2
(-1835 3585);
DISPLAY 0.680851 (-1835 3585);
PAINT MONO (-1835 3585);
FORCEPROP 0 LASTPIN (-1825 3625) $PN 224
J 2
(-1835 3635);
DISPLAY 0.680851 (-1835 3635);
PAINT MONO (-1835 3635);
FORCEPROP 0 LASTPIN (-1825 3675) $PN 226
J 2
(-1835 3685);
DISPLAY 0.680851 (-1835 3685);
PAINT MONO (-1835 3685);
FORCEPROP 0 LASTPIN (-1825 3725) $PN 228
J 2
(-1835 3735);
DISPLAY 0.680851 (-1835 3735);
PAINT MONO (-1835 3735);
FORCEPROP 0 LASTPIN (-1825 3775) $PN 230
J 2
(-1835 3785);
DISPLAY 0.680851 (-1835 3785);
PAINT MONO (-1835 3785);
FORCEPROP 0 LASTPIN (-1825 3825) $PN 233
J 2
(-1835 3835);
DISPLAY 0.680851 (-1835 3835);
PAINT MONO (-1835 3835);
FORCEPROP 0 LASTPIN (-1825 3875) $PN 235
J 2
(-1835 3885);
DISPLAY 0.680851 (-1835 3885);
PAINT MONO (-1835 3885);
FORCEPROP 0 LASTPIN (-1825 3925) $PN 237
J 2
(-1835 3935);
DISPLAY 0.680851 (-1835 3935);
PAINT MONO (-1835 3935);
FORCEPROP 0 LASTPIN (-1825 3975) $PN 240
J 2
(-1835 3985);
DISPLAY 0.680851 (-1835 3985);
PAINT MONO (-1835 3985);
FORCEPROP 0 LASTPIN (-1825 4025) $PN 242
J 2
(-1835 4035);
DISPLAY 0.680851 (-1835 4035);
PAINT MONO (-1835 4035);
FORCEPROP 0 LASTPIN (-1825 4075) $PN 244
J 2
(-1835 4085);
DISPLAY 0.680851 (-1835 4085);
PAINT MONO (-1835 4085);
FORCEPROP 0 LASTPIN (-1825 4125) $PN 246
J 2
(-1835 4135);
DISPLAY 0.680851 (-1835 4135);
PAINT MONO (-1835 4135);
FORCEPROP 0 LASTPIN (-1825 4175) $PN 248
J 2
(-1835 4185);
DISPLAY 0.680851 (-1835 4185);
PAINT MONO (-1835 4185);
FORCEPROP 0 LASTPIN (-1825 4225) $PN 251
J 2
(-1835 4235);
DISPLAY 0.680851 (-1835 4235);
PAINT MONO (-1835 4235);
FORCEPROP 0 LASTPIN (-1825 4275) $PN 253
J 2
(-1835 4285);
DISPLAY 0.680851 (-1835 4285);
PAINT MONO (-1835 4285);
FORCEPROP 0 LASTPIN (-1825 4325) $PN 255
J 2
(-1835 4335);
DISPLAY 0.680851 (-1835 4335);
PAINT MONO (-1835 4335);
FORCEPROP 0 LASTPIN (-1825 4375) $PN 257
J 2
(-1835 4385);
DISPLAY 0.680851 (-1835 4385);
PAINT MONO (-1835 4385);
FORCEPROP 0 LASTPIN (-1825 4425) $PN 259
J 2
(-1835 4435);
DISPLAY 0.680851 (-1835 4435);
PAINT MONO (-1835 4435);
FORCEPROP 0 LASTPIN (-1825 4475) $PN 262
J 2
(-1835 4485);
DISPLAY 0.680851 (-1835 4485);
PAINT MONO (-1835 4485);
FORCEPROP 0 LASTPIN (-1825 4525) $PN 264
J 2
(-1835 4535);
DISPLAY 0.680851 (-1835 4535);
PAINT MONO (-1835 4535);
FORCEPROP 0 LASTPIN (-1825 4575) $PN 266
J 2
(-1835 4585);
DISPLAY 0.680851 (-1835 4585);
PAINT MONO (-1835 4585);
FORCEPROP 0 LASTPIN (-1825 4625) $PN 268
J 2
(-1835 4635);
DISPLAY 0.680851 (-1835 4635);
PAINT MONO (-1835 4635);
FORCEPROP 0 LASTPIN (-1825 4675) $PN 270
J 2
(-1835 4685);
DISPLAY 0.680851 (-1835 4685);
PAINT MONO (-1835 4685);
FORCEPROP 0 LASTPIN (-1825 4725) $PN 273
J 2
(-1835 4735);
DISPLAY 0.680851 (-1835 4735);
PAINT MONO (-1835 4735);
FORCEPROP 0 LASTPIN (-1825 4775) $PN 275
J 2
(-1835 4785);
DISPLAY 0.680851 (-1835 4785);
PAINT MONO (-1835 4785);
FORCEPROP 0 LASTPIN (-1825 4825) $PN 277
J 2
(-1835 4835);
DISPLAY 0.680851 (-1835 4835);
PAINT MONO (-1835 4835);
FORCEPROP 0 LASTPIN (-1825 4875) $PN 279
J 2
(-1835 4885);
DISPLAY 0.680851 (-1835 4885);
PAINT MONO (-1835 4885);
FORCEPROP 0 LASTPIN (-1825 4925) $PN 281
J 2
(-1835 4935);
DISPLAY 0.680851 (-1835 4935);
PAINT MONO (-1835 4935);
FORCEPROP 0 LASTPIN (-1825 4975) $PN 284
J 2
(-1835 4985);
DISPLAY 0.680851 (-1835 4985);
PAINT MONO (-1835 4985);
FORCEPROP 0 LASTPIN (-1825 5025) $PN 286
J 2
(-1835 5035);
DISPLAY 0.680851 (-1835 5035);
PAINT MONO (-1835 5035);
FORCEPROP 0 LASTPIN (-1825 5075) $PN 288
J 2
(-1835 5085);
DISPLAY 0.680851 (-1835 5085);
PAINT MONO (-1835 5085);
FORCEPROP 2 LAST PART_TYPE SMLF
J 0
(-1675 5650);
DISPLAY 1.021277 (-1675 5650);
FORCEPROP 1 LAST MATERIAL IO
J 0
(-1675 5400);
DISPLAY 0.468085 (-1675 5400);
PAINT SKYBLUE (-1675 5400);
FORCEPROP 2 LAST VALUE SCONN288_DDR506112002KQ
J 0
(-1675 5600);
DISPLAY 0.489362 (-1675 5600);
PAINT SKYBLUE (-1675 5600);
FORCEPROP 2 LAST CDS_LIB pure_quanta
J 0
(-1225 3575);
DISPLAY INVISIBLE (-1225 3575);
FORCEPROP 1 LAST NEEDS_NO_SIZE TRUE
J 0
(-1225 3575);
DISPLAY 0.723404 (-1225 3575);
PAINT GREEN (-1225 3575);
DISPLAY INVISIBLE (-1225 3575);
FORCEPROP 1 LAST CDS_LMAN_SYM_OUTLINE -450,1800,450,-1750
J 0
(-1225 3575);
DISPLAY 0.468085 (-1225 3575);
PAINT GREEN (-1225 3575);
DISPLAY INVISIBLE (-1225 3575);
FORCEPROP 1 LAST PATH I352
J 0
(-1225 3575);
DISPLAY 0.723404 (-1225 3575);
PAINT GREEN (-1225 3575);
DISPLAY INVISIBLE (-1225 3575);
FORCEPROP 1 LAST PART_NUMBER DFHST8FS479
J 0
(-1675 5475);
DISPLAY 0.468085 (-1675 5475);
PAINT SKYBLUE (-1675 5475);
DISPLAY INVISIBLE (-1675 5475);
FORCEADD OFFPAGE..5
(-8525 3175);
FORCEPROP 2 LAST $XR0 11 
J 0
(-8779 3175);
DISPLAY 0.638298 (-8779 3175);
PAINT MONO (-8779 3175);
FORCEPROP 2 LAST CDS_LIB mstr_standard
J 0
(-8525 3175);
DISPLAY INVISIBLE (-8525 3175);
FORCEPROP 1 LAST OFFPAGE TRUE
J 0
(-8200 3050);
DISPLAY 0.872340 (-8200 3050);
PAINT GREEN (-8200 3050);
DISPLAY INVISIBLE (-8200 3050);
FORCEPROP 1 LAST COMMENT_BODY TRUE
J 0
(-8425 3100);
DISPLAY 0.872340 (-8425 3100);
PAINT GREEN (-8425 3100);
DISPLAY INVISIBLE (-8425 3100);
FORCEPROP 2 LAST PATH I353
J 0
(-8475 3250);
DISPLAY 1.021277 (-8475 3250);
DISPLAY INVISIBLE (-8475 3250);
FORCEADD OFFPAGE..1
(-8575 2775);
FORCEPROP 2 LAST $XR5 91 
J 0
(-9307 2775);
DISPLAY 0.638298 (-9307 2775);
PAINT MONO (-9307 2775);
FORCEPROP 2 LAST $XR4 90 
J 0
(-9217 2775);
DISPLAY 0.638298 (-9217 2775);
PAINT MONO (-9217 2775);
FORCEPROP 2 LAST $XR3 89 
J 0
(-9127 2775);
DISPLAY 0.638298 (-9127 2775);
PAINT MONO (-9127 2775);
FORCEPROP 2 LAST $XR2 88 
J 0
(-9037 2775);
DISPLAY 0.638298 (-9037 2775);
PAINT MONO (-9037 2775);
FORCEPROP 2 LAST $XR1 86 
J 0
(-8947 2775);
DISPLAY 0.638298 (-8947 2775);
PAINT MONO (-8947 2775);
FORCEPROP 2 LAST $XR0 159 
J 0
(-8857 2775);
DISPLAY 0.638298 (-8857 2775);
PAINT MONO (-8857 2775);
FORCEPROP 2 LAST CDS_LIB mstr_standard
J 0
(-8575 2775);
DISPLAY 0.808511 (-8575 2775);
DISPLAY INVISIBLE (-8575 2775);
FORCEPROP 1 LAST OFFPAGE TRUE
J 0
(-8250 2650);
DISPLAY 0.872340 (-8250 2650);
PAINT GREEN (-8250 2650);
DISPLAY INVISIBLE (-8250 2650);
FORCEPROP 1 LAST COMMENT_BODY TRUE
J 0
(-8450 2675);
DISPLAY 0.872340 (-8450 2675);
PAINT GREEN (-8450 2675);
DISPLAY INVISIBLE (-8450 2675);
FORCEPROP 2 LAST PATH I354
J 0
(-8850 2825);
DISPLAY 1.021277 (-8850 2825);
DISPLAY INVISIBLE (-8850 2825);
FORCEADD GND..1
(-9050 3100);
FORCEPROP 3 LASTPIN (-9050 3150) SIG_NAME GND\g
J 0
(-9040 3160);
DISPLAY 0.659574 (-9040 3160);
PAINT MONO (-9040 3160);
DISPLAY INVISIBLE (-9040 3160);
FORCEPROP 2 LAST ROOM MEM_EFGH_DECOUPLING_CAPS
J 0
(-9025 3175);
DISPLAY 0.659574 (-9025 3175);
PAINT RED (-9025 3175);
DISPLAY INVISIBLE (-9025 3175);
FORCEPROP 1 LAST VOLTAGE 0
J 0
(-9070 3195);
DISPLAY 0.829787 (-9070 3195);
PAINT SKYBLUE (-9070 3195);
DISPLAY INVISIBLE (-9070 3195);
FORCEPROP 2 LAST CDS_LIB mstr_symbols
J 0
(-9050 3100);
DISPLAY 0.808511 (-9050 3100);
DISPLAY INVISIBLE (-9050 3100);
FORCEPROP 1 LAST SIZE 1B
J 0
(-8975 3050);
DISPLAY 0.723404 (-8975 3050);
PAINT GREEN (-8975 3050);
DISPLAY INVISIBLE (-8975 3050);
FORCEPROP 2 LAST BOM_COST MEM
J 0
(-9025 3225);
DISPLAY 0.659574 (-9025 3225);
DISPLAY INVISIBLE (-9025 3225);
FORCEPROP 1 LAST BODY_TYPE PLUMBING
J 0
(-9095 3057);
DISPLAY 0.276596 (-9095 3057);
PAINT GREEN (-9095 3057);
DISPLAY INVISIBLE (-9095 3057);
FORCEPROP 1 LAST HDL_POWER GND
J 0
(-9050 3250);
DISPLAY 0.723404 (-9050 3250);
PAINT GREEN (-9050 3250);
DISPLAY INVISIBLE (-9050 3250);
FORCEPROP 1 LAST PATH I361
J 0
(-8975 3100);
DISPLAY 0.872340 (-8975 3100);
PAINT AQUA (-8975 3100);
DISPLAY INVISIBLE (-8975 3100);
FORCEADD Q_CAP..1
R 2
(-9050 3325);
FORCEPROP 1 LAST LOCATION C92
J 2
(-9100 3425);
DISPLAY 0.489362 (-9100 3425);
PAINT SKYBLUE (-9100 3425);
FORCEPROP 0 LAST $SEC 1
J 0
(-9100 3475);
DISPLAY 0.680851 (-9100 3475);
PAINT MONO (-9100 3475);
DISPLAY INVISIBLE (-9100 3475);
FORCEPROP 0 LAST CDS_SEC 1
J 0
(-9100 3475);
DISPLAY 1.021277 (-9100 3475);
DISPLAY INVISIBLE (-9100 3475);
FORCEPROP 1 LASTPIN (-9050 3425) $PN 1
J 2
(-9060 3405);
DISPLAY 0.489362 (-9060 3405);
PAINT MONO (-9060 3405);
FORCEPROP 1 LASTPIN (-9050 3225) $PN 2
J 2
(-9060 3205);
DISPLAY 0.489362 (-9060 3205);
PAINT MONO (-9060 3205);
FORCEPROP 1 LAST TOLERANCE 10%
J 2
(-9100 3275);
DISPLAY 0.489362 (-9100 3275);
PAINT SKYBLUE (-9100 3275);
FORCEPROP 1 LAST VOLTAGE 25V
J 2
(-9100 3325);
DISPLAY 0.489362 (-9100 3325);
PAINT SKYBLUE (-9100 3325);
FORCEPROP 1 LAST PACK_TYPE 0402
J 2
(-9100 3125);
DISPLAY 0.489362 (-9100 3125);
PAINT SKYBLUE (-9100 3125);
FORCEPROP 1 LAST MATERIAL X7R
J 2
(-9100 3225);
DISPLAY 0.489362 (-9100 3225);
PAINT SKYBLUE (-9100 3225);
FORCEPROP 1 LAST VALUE 0.1UF
J 2
(-9100 3375);
DISPLAY 0.489362 (-9100 3375);
PAINT SKYBLUE (-9100 3375);
FORCEPROP 0 LAST BOM_COST MEM
J 2
(-9105 3470);
DISPLAY 0.595745 (-9105 3470);
PAINT MONO (-9105 3470);
DISPLAY INVISIBLE (-9105 3470);
FORCEPROP 2 LAST CDS_LIB pure_quanta
J 0
(-9050 3325);
DISPLAY INVISIBLE (-9050 3325);
FORCEPROP 2 LAST ROOM 
J 2
(-9105 3470);
DISPLAY 0.595745 (-9105 3470);
PAINT RED (-9105 3470);
DISPLAY INVISIBLE (-9105 3470);
FORCEPROP 1 LAST PATH I362
J 2
(-9100 3475);
DISPLAY 0.978723 (-9100 3475);
PAINT WHITE (-9100 3475);
DISPLAY INVISIBLE (-9100 3475);
FORCEPROP 1 LAST PART_NUMBER CH4104K1B00
J 2
(-9100 3175);
DISPLAY 0.489362 (-9100 3175);
PAINT SKYBLUE (-9100 3175);
DISPLAY INVISIBLE (-9100 3175);
FORCEADD OFFPAGE..6
(-9175 2275);
FORCEPROP 2 LAST $XR4 91 
J 0
(-9454 2311);
DISPLAY 0.638298 (-9454 2311);
PAINT MONO (-9454 2311);
FORCEPROP 2 LAST $XR3 90 
J 0
(-9544 2239);
DISPLAY 0.638298 (-9544 2239);
PAINT MONO (-9544 2239);
FORCEPROP 2 LAST $XR2 89 
J 0
(-9454 2239);
DISPLAY 0.638298 (-9454 2239);
PAINT MONO (-9454 2239);
FORCEPROP 2 LAST $XR1 88 
J 0
(-9544 2275);
DISPLAY 0.638298 (-9544 2275);
PAINT MONO (-9544 2275);
FORCEPROP 2 LAST $XR0 86 
J 0
(-9454 2275);
DISPLAY 0.638298 (-9454 2275);
PAINT MONO (-9454 2275);
FORCEPROP 2 LAST CDS_LIB mstr_standard
J 0
(-9175 2275);
DISPLAY 0.808511 (-9175 2275);
DISPLAY INVISIBLE (-9175 2275);
FORCEPROP 1 LAST OFFPAGE TRUE
J 0
(-8850 2150);
DISPLAY 0.872340 (-8850 2150);
PAINT GREEN (-8850 2150);
DISPLAY INVISIBLE (-8850 2150);
FORCEPROP 1 LAST COMMENT_BODY TRUE
J 0
(-9075 2200);
DISPLAY 0.872340 (-9075 2200);
PAINT GREEN (-9075 2200);
DISPLAY INVISIBLE (-9075 2200);
FORCEPROP 2 LAST PATH I363
J 0
(-9125 2350);
DISPLAY 1.021277 (-9125 2350);
DISPLAY INVISIBLE (-9125 2350);
FORCEADD Q_RES..1
R 2
(-8675 2275);
FORCEPROP 1 LAST LOCATION R292
J 2
(-8650 2300);
DISPLAY 0.489362 (-8650 2300);
PAINT SKYBLUE (-8650 2300);
FORCEPROP 0 LAST $SEC 1
J 0
(-8650 2350);
DISPLAY 0.680851 (-8650 2350);
PAINT MONO (-8650 2350);
DISPLAY INVISIBLE (-8650 2350);
FORCEPROP 0 LAST CDS_SEC 1
J 0
(-8650 2350);
DISPLAY 1.021277 (-8650 2350);
DISPLAY INVISIBLE (-8650 2350);
FORCEPROP 1 LASTPIN (-8575 2275) $PN 1
J 2
(-8587 2287);
DISPLAY 0.489362 (-8587 2287);
PAINT MONO (-8587 2287);
FORCEPROP 1 LASTPIN (-8775 2275) $PN 2
J 2
(-8737 2287);
DISPLAY 0.489362 (-8737 2287);
PAINT MONO (-8737 2287);
FORCEPROP 1 LAST VALUE 1K
J 0
(-8675 2225);
DISPLAY 0.489362 (-8675 2225);
PAINT SKYBLUE (-8675 2225);
FORCEPROP 1 LAST PACK_TYPE 0402LF
J 0
(-8850 2200);
DISPLAY 0.489362 (-8850 2200);
PAINT SKYBLUE (-8850 2200);
DISPLAY INVISIBLE (-8850 2200);
FORCEPROP 1 LAST MATERIAL CHIP
J 0
(-8850 2250);
DISPLAY 0.489362 (-8850 2250);
PAINT SKYBLUE (-8850 2250);
DISPLAY INVISIBLE (-8850 2250);
FORCEPROP 1 LAST WATTAGE 1/16W
J 0
(-8600 2200);
DISPLAY 0.489362 (-8600 2200);
PAINT SKYBLUE (-8600 2200);
DISPLAY INVISIBLE (-8600 2200);
FORCEPROP 2 LAST CDS_LIB pure_quanta
J 0
(-8675 2275);
DISPLAY INVISIBLE (-8675 2275);
FORCEPROP 2 LAST BOM_COST MEM
J 0
(-8700 2425);
DISPLAY 0.744681 (-8700 2425);
PAINT WHITE (-8700 2425);
DISPLAY INVISIBLE (-8700 2425);
FORCEPROP 1 LAST TOLERANCE 1%
J 2
(-8550 2250);
DISPLAY 0.489362 (-8550 2250);
PAINT SKYBLUE (-8550 2250);
DISPLAY INVISIBLE (-8550 2250);
FORCEPROP 2 LAST ROOM 
J 0
(-8700 2375);
DISPLAY 0.744681 (-8700 2375);
PAINT RED (-8700 2375);
DISPLAY INVISIBLE (-8700 2375);
FORCEPROP 1 LAST PATH I364
J 2
(-8625 2425);
DISPLAY 0.978723 (-8625 2425);
PAINT WHITE (-8625 2425);
DISPLAY INVISIBLE (-8625 2425);
FORCEPROP 1 LAST PART_NUMBER CS21002FB06
J 0
(-8775 2325);
DISPLAY 0.489362 (-8775 2325);
PAINT SKYBLUE (-8775 2325);
DISPLAY INVISIBLE (-8775 2325);
FORCEADD Q_RES..2
(-8550 2425);
FORCEPROP 1 LAST LOCATION R90
J 0
(-8505 2550);
DISPLAY 0.489362 (-8505 2550);
PAINT SKYBLUE (-8505 2550);
FORCEPROP 0 LAST $SEC 1
J 0
(-8500 2600);
DISPLAY 0.680851 (-8500 2600);
PAINT MONO (-8500 2600);
DISPLAY INVISIBLE (-8500 2600);
FORCEPROP 0 LAST CDS_SEC 1
J 0
(-8500 2600);
DISPLAY 1.021277 (-8500 2600);
DISPLAY INVISIBLE (-8500 2600);
FORCEPROP 1 LASTPIN (-8550 2525) $PN 1
J 0
(-8545 2487);
DISPLAY 0.489362 (-8545 2487);
PAINT MONO (-8545 2487);
FORCEPROP 1 LASTPIN (-8550 2325) $PN 2
J 0
(-8545 2335);
DISPLAY 0.489362 (-8545 2335);
PAINT MONO (-8545 2335);
FORCEPROP 1 LAST WATTAGE 1/16W
J 0
(-8500 2450);
DISPLAY 0.489362 (-8500 2450);
PAINT SKYBLUE (-8500 2450);
FORCEPROP 1 LAST PACK_TYPE 0402LF
J 0
(-8500 2375);
DISPLAY 0.489362 (-8500 2375);
PAINT SKYBLUE (-8500 2375);
FORCEPROP 1 LAST VALUE 1K
J 0
(-8505 2500);
DISPLAY 0.489362 (-8505 2500);
PAINT SKYBLUE (-8505 2500);
FORCEPROP 1 LAST MATERIAL EMPTY
J 0
(-8500 2425);
DISPLAY 0.489362 (-8500 2425);
PAINT RED (-8500 2425);
FORCEPROP 1 LAST TOLERANCE 1%
J 0
(-8500 2475);
DISPLAY 0.489362 (-8500 2475);
PAINT SKYBLUE (-8500 2475);
FORCEPROP 2 LAST BOM_COST MEM
J 0
(-8500 2600);
DISPLAY 0.808511 (-8500 2600);
DISPLAY INVISIBLE (-8500 2600);
FORCEPROP 2 LAST CDS_LIB pure_quanta
J 2
(-8550 2425);
DISPLAY INVISIBLE (-8550 2425);
FORCEPROP 2 LAST ROOM 
J 0
(-8500 2650);
DISPLAY 0.808511 (-8500 2650);
PAINT RED (-8500 2650);
DISPLAY INVISIBLE (-8500 2650);
FORCEPROP 1 LAST PATH I365
J 0
(-8500 2600);
DISPLAY 0.978723 (-8500 2600);
PAINT WHITE (-8500 2600);
DISPLAY INVISIBLE (-8500 2600);
FORCEPROP 1 LAST PART_NUMBER CS21002FB06
J 0
(-8500 2400);
DISPLAY 0.489362 (-8500 2400);
PAINT SKYBLUE (-8500 2400);
DISPLAY INVISIBLE (-8500 2400);
FORCEADD VCC_CORE..1
(-8550 2600);
FORCEPROP 3 LASTPIN (-8550 2550) SIG_NAME P3V3\g
J 0
(-8540 2560);
DISPLAY 0.659574 (-8540 2560);
PAINT MONO (-8540 2560);
DISPLAY INVISIBLE (-8540 2560);
FORCEPROP 1 LAST HDL_POWER P3V3
J 1
(-8550 2650);
DISPLAY 0.489362 (-8550 2650);
PAINT GREEN (-8550 2650);
FORCEPROP 2 LAST ROOM PVCCINFAON_CPU0_CTRL
J 0
(-8550 2700);
DISPLAY 0.808511 (-8550 2700);
PAINT RED (-8550 2700);
DISPLAY INVISIBLE (-8550 2700);
FORCEPROP 0 LAST VOLTAGE 3.3
J 0
(-8825 2750);
DISPLAY 1.021277 (-8825 2750);
PAINT SKYBLUE (-8825 2750);
DISPLAY INVISIBLE (-8825 2750);
FORCEPROP 2 LAST CDS_LIB mstr_symbols
J 0
(-8550 2600);
DISPLAY INVISIBLE (-8550 2600);
FORCEPROP 1 LAST PATH I366
J 0
(-8500 2625);
DISPLAY 0.872340 (-8500 2625);
PAINT AQUA (-8500 2625);
DISPLAY INVISIBLE (-8500 2625);
FORCEADD SCONN288_DDR506112002KQ..2
(-4600 3650);
FORCEPROP 1 LAST LOCATION J15
J 0
(-5200 4975);
DISPLAY 0.574468 (-5200 4975);
PAINT SKYBLUE (-5200 4975);
FORCEPROP 0 LAST $SEC 2
J 0
(-5200 5150);
DISPLAY 0.680851 (-5200 5150);
PAINT MONO (-5200 5150);
DISPLAY INVISIBLE (-5200 5150);
FORCEPROP 0 LAST CDS_SEC 2
J 0
(-5050 5125);
DISPLAY 1.021277 (-5050 5125);
DISPLAY INVISIBLE (-5050 5125);
FORCEPROP 0 LASTPIN (-3850 3700) $PN 12
J 0
(-3840 3710);
DISPLAY 0.680851 (-3840 3710);
PAINT MONO (-3840 3710);
FORCEPROP 0 LASTPIN (-3850 3750) $PN 11
J 0
(-3840 3760);
DISPLAY 0.680851 (-3840 3760);
PAINT MONO (-3840 3760);
FORCEPROP 0 LASTPIN (-3850 2650) $PN 105
J 0
(-3840 2660);
DISPLAY 0.680851 (-3840 2660);
PAINT MONO (-3840 2660);
FORCEPROP 0 LASTPIN (-3850 2700) $PN 104
J 0
(-3840 2710);
DISPLAY 0.680851 (-3840 2710);
PAINT MONO (-3840 2710);
FORCEPROP 0 LASTPIN (-3850 3800) $PN 23
J 0
(-3840 3810);
DISPLAY 0.680851 (-3840 3810);
PAINT MONO (-3840 3810);
FORCEPROP 0 LASTPIN (-3850 3850) $PN 22
J 0
(-3840 3860);
DISPLAY 0.680851 (-3840 3860);
PAINT MONO (-3840 3860);
FORCEPROP 0 LASTPIN (-3850 2750) $PN 116
J 0
(-3840 2760);
DISPLAY 0.680851 (-3840 2760);
PAINT MONO (-3840 2760);
FORCEPROP 0 LASTPIN (-3850 2800) $PN 115
J 0
(-3840 2810);
DISPLAY 0.680851 (-3840 2810);
PAINT MONO (-3840 2810);
FORCEPROP 0 LASTPIN (-3850 3900) $PN 34
J 0
(-3840 3910);
DISPLAY 0.680851 (-3840 3910);
PAINT MONO (-3840 3910);
FORCEPROP 0 LASTPIN (-3850 3950) $PN 33
J 0
(-3840 3960);
DISPLAY 0.680851 (-3840 3960);
PAINT MONO (-3840 3960);
FORCEPROP 0 LASTPIN (-3850 2850) $PN 127
J 0
(-3840 2860);
DISPLAY 0.680851 (-3840 2860);
PAINT MONO (-3840 2860);
FORCEPROP 0 LASTPIN (-3850 2900) $PN 126
J 0
(-3840 2910);
DISPLAY 0.680851 (-3840 2910);
PAINT MONO (-3840 2910);
FORCEPROP 0 LASTPIN (-3850 4000) $PN 45
J 0
(-3840 4010);
DISPLAY 0.680851 (-3840 4010);
PAINT MONO (-3840 4010);
FORCEPROP 0 LASTPIN (-3850 4050) $PN 44
J 0
(-3840 4060);
DISPLAY 0.680851 (-3840 4060);
PAINT MONO (-3840 4060);
FORCEPROP 0 LASTPIN (-3850 2950) $PN 138
J 0
(-3840 2960);
DISPLAY 0.680851 (-3840 2960);
PAINT MONO (-3840 2960);
FORCEPROP 0 LASTPIN (-3850 3000) $PN 137
J 0
(-3840 3010);
DISPLAY 0.680851 (-3840 3010);
PAINT MONO (-3840 3010);
FORCEPROP 0 LASTPIN (-3850 4100) $PN 56
J 0
(-3840 4110);
DISPLAY 0.680851 (-3840 4110);
PAINT MONO (-3840 4110);
FORCEPROP 0 LASTPIN (-3850 4150) $PN 55
J 0
(-3840 4160);
DISPLAY 0.680851 (-3840 4160);
PAINT MONO (-3840 4160);
FORCEPROP 0 LASTPIN (-3850 3050) $PN 238
J 0
(-3840 3060);
DISPLAY 0.680851 (-3840 3060);
PAINT MONO (-3840 3060);
FORCEPROP 0 LASTPIN (-3850 3100) $PN 239
J 0
(-3840 3110);
DISPLAY 0.680851 (-3840 3110);
PAINT MONO (-3840 3110);
FORCEPROP 0 LASTPIN (-3850 4200) $PN 156
J 0
(-3840 4210);
DISPLAY 0.680851 (-3840 4210);
PAINT MONO (-3840 4210);
FORCEPROP 0 LASTPIN (-3850 4250) $PN 157
J 0
(-3840 4260);
DISPLAY 0.680851 (-3840 4260);
PAINT MONO (-3840 4260);
FORCEPROP 0 LASTPIN (-3850 3150) $PN 249
J 0
(-3840 3160);
DISPLAY 0.680851 (-3840 3160);
PAINT MONO (-3840 3160);
FORCEPROP 0 LASTPIN (-3850 3200) $PN 250
J 0
(-3840 3210);
DISPLAY 0.680851 (-3840 3210);
PAINT MONO (-3840 3210);
FORCEPROP 0 LASTPIN (-3850 4300) $PN 167
J 0
(-3840 4310);
DISPLAY 0.680851 (-3840 4310);
PAINT MONO (-3840 4310);
FORCEPROP 0 LASTPIN (-3850 4350) $PN 168
J 0
(-3840 4360);
DISPLAY 0.680851 (-3840 4360);
PAINT MONO (-3840 4360);
FORCEPROP 0 LASTPIN (-3850 3250) $PN 260
J 0
(-3840 3260);
DISPLAY 0.680851 (-3840 3260);
PAINT MONO (-3840 3260);
FORCEPROP 0 LASTPIN (-3850 3300) $PN 261
J 0
(-3840 3310);
DISPLAY 0.680851 (-3840 3310);
PAINT MONO (-3840 3310);
FORCEPROP 0 LASTPIN (-3850 4400) $PN 178
J 0
(-3840 4410);
DISPLAY 0.680851 (-3840 4410);
PAINT MONO (-3840 4410);
FORCEPROP 0 LASTPIN (-3850 4450) $PN 179
J 0
(-3840 4460);
DISPLAY 0.680851 (-3840 4460);
PAINT MONO (-3840 4460);
FORCEPROP 0 LASTPIN (-3850 3350) $PN 271
J 0
(-3840 3360);
DISPLAY 0.680851 (-3840 3360);
PAINT MONO (-3840 3360);
FORCEPROP 0 LASTPIN (-3850 3400) $PN 272
J 0
(-3840 3410);
DISPLAY 0.680851 (-3840 3410);
PAINT MONO (-3840 3410);
FORCEPROP 0 LASTPIN (-3850 4500) $PN 189
J 0
(-3840 4510);
DISPLAY 0.680851 (-3840 4510);
PAINT MONO (-3840 4510);
FORCEPROP 0 LASTPIN (-3850 4550) $PN 190
J 0
(-3840 4560);
DISPLAY 0.680851 (-3840 4560);
PAINT MONO (-3840 4560);
FORCEPROP 0 LASTPIN (-3850 3450) $PN 282
J 0
(-3840 3460);
DISPLAY 0.680851 (-3840 3460);
PAINT MONO (-3840 3460);
FORCEPROP 0 LASTPIN (-3850 3500) $PN 283
J 0
(-3840 3510);
DISPLAY 0.680851 (-3840 3510);
PAINT MONO (-3840 3510);
FORCEPROP 0 LASTPIN (-3850 4600) $PN 200
J 0
(-3840 4610);
DISPLAY 0.680851 (-3840 4610);
PAINT MONO (-3840 4610);
FORCEPROP 0 LASTPIN (-3850 4650) $PN 201
J 0
(-3840 4660);
DISPLAY 0.680851 (-3840 4660);
PAINT MONO (-3840 4660);
FORCEPROP 0 LASTPIN (-3850 3550) $PN 94
J 0
(-3840 3560);
DISPLAY 0.680851 (-3840 3560);
PAINT MONO (-3840 3560);
FORCEPROP 0 LASTPIN (-3850 3600) $PN 93
J 0
(-3840 3610);
DISPLAY 0.680851 (-3840 3610);
PAINT MONO (-3840 3610);
FORCEPROP 2 LAST PART_TYPE SMLF
J 0
(-5200 5100);
DISPLAY 1.021277 (-5200 5100);
FORCEPROP 2 LAST VALUE SCONN288_DDR506112002KQ
J 0
(-5200 5050);
DISPLAY 0.489362 (-5200 5050);
PAINT SKYBLUE (-5200 5050);
FORCEPROP 1 LAST MATERIAL IO
J 0
(-5200 4825);
DISPLAY 0.468085 (-5200 4825);
PAINT SKYBLUE (-5200 4825);
FORCEPROP 2 LAST CDS_LIB pure_quanta
J 0
(-4600 3650);
DISPLAY INVISIBLE (-4600 3650);
FORCEPROP 1 LAST NEEDS_NO_SIZE TRUE
J 0
(-4600 3650);
DISPLAY 0.723404 (-4600 3650);
PAINT GREEN (-4600 3650);
DISPLAY INVISIBLE (-4600 3650);
FORCEPROP 1 LAST CDS_LMAN_SYM_OUTLINE -600,1150,600,-1150
J 0
(-4600 3650);
DISPLAY 0.468085 (-4600 3650);
PAINT GREEN (-4600 3650);
DISPLAY INVISIBLE (-4600 3650);
FORCEPROP 1 LAST PATH I367
J 0
(-4600 3650);
DISPLAY 0.723404 (-4600 3650);
PAINT GREEN (-4600 3650);
DISPLAY INVISIBLE (-4600 3650);
FORCEPROP 1 LAST PART_NUMBER DFHST8FS479
J 0
(-5200 4900);
DISPLAY 0.468085 (-5200 4900);
PAINT SKYBLUE (-5200 4900);
DISPLAY INVISIBLE (-5200 4900);
FORCEADD GND..1
(-2825 5225);
FORCEPROP 3 LASTPIN (-2825 5275) SIG_NAME GND\g
J 0
(-2815 5285);
DISPLAY 0.659574 (-2815 5285);
PAINT MONO (-2815 5285);
DISPLAY INVISIBLE (-2815 5285);
FORCEPROP 2 LAST ROOM MEM_EFGH_DECOUPLING_CAPS
J 0
(-2800 5300);
DISPLAY 0.659574 (-2800 5300);
PAINT RED (-2800 5300);
DISPLAY INVISIBLE (-2800 5300);
FORCEPROP 2 LAST CDS_LIB pure_quanta_power
J 0
(-2825 5225);
DISPLAY INVISIBLE (-2825 5225);
FORCEPROP 2 LAST BOM_COST MEM
J 0
(-2800 5350);
DISPLAY 0.659574 (-2800 5350);
DISPLAY INVISIBLE (-2800 5350);
FORCEPROP 1 LAST SIZE 1B
J 0
(-2750 5175);
DISPLAY 0.723404 (-2750 5175);
PAINT GREEN (-2750 5175);
DISPLAY INVISIBLE (-2750 5175);
FORCEPROP 1 LAST HDL_POWER GND
J 0
(-2825 5375);
DISPLAY 0.723404 (-2825 5375);
PAINT GREEN (-2825 5375);
DISPLAY INVISIBLE (-2825 5375);
FORCEPROP 1 LAST PATH I368
J 0
(-2750 5225);
DISPLAY 0.872340 (-2750 5225);
PAINT AQUA (-2750 5225);
DISPLAY INVISIBLE (-2750 5225);
FORCEADD Q_CAP..1
R 2
(-2825 5575);
FORCEPROP 1 LAST LOCATION C143
J 2
(-2875 5675);
DISPLAY 0.489362 (-2875 5675);
PAINT SKYBLUE (-2875 5675);
FORCEPROP 0 LAST $SEC 1
J 0
(-2875 5725);
DISPLAY 0.680851 (-2875 5725);
PAINT MONO (-2875 5725);
DISPLAY INVISIBLE (-2875 5725);
FORCEPROP 0 LAST CDS_SEC 1
J 0
(-2875 5725);
DISPLAY 0.680851 (-2875 5725);
DISPLAY INVISIBLE (-2875 5725);
FORCEPROP 1 LASTPIN (-2825 5675) $PN 1
J 2
(-2835 5655);
DISPLAY 0.489362 (-2835 5655);
PAINT MONO (-2835 5655);
FORCEPROP 1 LASTPIN (-2825 5475) $PN 2
J 2
(-2835 5455);
DISPLAY 0.489362 (-2835 5455);
PAINT MONO (-2835 5455);
FORCEPROP 1 LAST MATERIAL X6S
J 2
(-2875 5475);
DISPLAY 0.489362 (-2875 5475);
PAINT SKYBLUE (-2875 5475);
FORCEPROP 1 LAST TOLERANCE 10%
J 2
(-2875 5525);
DISPLAY 0.489362 (-2875 5525);
PAINT SKYBLUE (-2875 5525);
FORCEPROP 1 LAST VALUE 10UF
J 2
(-2875 5625);
DISPLAY 0.489362 (-2875 5625);
PAINT SKYBLUE (-2875 5625);
FORCEPROP 1 LAST VOLTAGE 25V
J 2
(-2875 5575);
DISPLAY 0.489362 (-2875 5575);
PAINT SKYBLUE (-2875 5575);
FORCEPROP 1 LAST PACK_TYPE C0805
J 2
(-2875 5375);
DISPLAY 0.489362 (-2875 5375);
PAINT SKYBLUE (-2875 5375);
FORCEPROP 2 LAST CDS_LIB pure_quanta
J 0
(-2825 5575);
DISPLAY INVISIBLE (-2825 5575);
FORCEPROP 0 LAST BOM_COST MEM
J 2
(-2880 5720);
DISPLAY 0.595745 (-2880 5720);
PAINT MONO (-2880 5720);
DISPLAY INVISIBLE (-2880 5720);
FORCEPROP 2 LAST ROOM 
J 2
(-2880 5720);
DISPLAY 0.595745 (-2880 5720);
PAINT RED (-2880 5720);
DISPLAY INVISIBLE (-2880 5720);
FORCEPROP 1 LAST PATH I369
J 2
(-2875 5725);
DISPLAY 0.978723 (-2875 5725);
PAINT WHITE (-2875 5725);
DISPLAY INVISIBLE (-2875 5725);
FORCEPROP 1 LAST PART_NUMBER CH6104KEA00
J 2
(-2875 5425);
DISPLAY 0.489362 (-2875 5425);
PAINT SKYBLUE (-2875 5425);
DISPLAY INVISIBLE (-2875 5425);
FORCEADD Q_CAP..1
R 2
(-2250 5575);
FORCEPROP 1 LAST LOCATION C145
J 2
(-2300 5675);
DISPLAY 0.489362 (-2300 5675);
PAINT SKYBLUE (-2300 5675);
FORCEPROP 0 LAST $SEC 1
J 0
(-2300 5725);
DISPLAY 0.680851 (-2300 5725);
PAINT MONO (-2300 5725);
DISPLAY INVISIBLE (-2300 5725);
FORCEPROP 0 LAST CDS_SEC 1
J 0
(-2300 5725);
DISPLAY 0.680851 (-2300 5725);
DISPLAY INVISIBLE (-2300 5725);
FORCEPROP 1 LASTPIN (-2250 5675) $PN 1
J 2
(-2260 5655);
DISPLAY 0.489362 (-2260 5655);
PAINT MONO (-2260 5655);
FORCEPROP 1 LASTPIN (-2250 5475) $PN 2
J 2
(-2260 5455);
DISPLAY 0.489362 (-2260 5455);
PAINT MONO (-2260 5455);
FORCEPROP 1 LAST MATERIAL X6S
J 2
(-2300 5475);
DISPLAY 0.489362 (-2300 5475);
PAINT SKYBLUE (-2300 5475);
FORCEPROP 1 LAST TOLERANCE 10%
J 2
(-2300 5525);
DISPLAY 0.489362 (-2300 5525);
PAINT SKYBLUE (-2300 5525);
FORCEPROP 1 LAST VALUE 10UF
J 2
(-2300 5625);
DISPLAY 0.489362 (-2300 5625);
PAINT SKYBLUE (-2300 5625);
FORCEPROP 1 LAST VOLTAGE 25V
J 2
(-2300 5575);
DISPLAY 0.489362 (-2300 5575);
PAINT SKYBLUE (-2300 5575);
FORCEPROP 1 LAST PACK_TYPE C0805
J 2
(-2300 5375);
DISPLAY 0.489362 (-2300 5375);
PAINT SKYBLUE (-2300 5375);
FORCEPROP 2 LAST CDS_LIB pure_quanta
J 0
(-2250 5575);
DISPLAY INVISIBLE (-2250 5575);
FORCEPROP 0 LAST BOM_COST MEM
J 2
(-2305 5720);
DISPLAY 0.595745 (-2305 5720);
PAINT MONO (-2305 5720);
DISPLAY INVISIBLE (-2305 5720);
FORCEPROP 2 LAST ROOM 
J 2
(-2305 5720);
DISPLAY 0.595745 (-2305 5720);
PAINT RED (-2305 5720);
DISPLAY INVISIBLE (-2305 5720);
FORCEPROP 1 LAST PATH I370
J 2
(-2300 5725);
DISPLAY 0.978723 (-2300 5725);
PAINT WHITE (-2300 5725);
DISPLAY INVISIBLE (-2300 5725);
FORCEPROP 1 LAST PART_NUMBER CH6104KEA00
J 2
(-2300 5425);
DISPLAY 0.489362 (-2300 5425);
PAINT SKYBLUE (-2300 5425);
DISPLAY INVISIBLE (-2300 5425);
FORCEADD UNIVERSAL_POWER..1
(-2825 5900);
FORCEPROP 3 LASTPIN (-2825 5850) SIG_NAME P12V_MEM_CPU0\g
J 0
(-2815 5860);
DISPLAY 0.659574 (-2815 5860);
PAINT MONO (-2815 5860);
DISPLAY INVISIBLE (-2815 5860);
FORCEPROP 1 LAST HDL_POWER P12V_MEM_CPU0
J 1
(-2850 5950);
DISPLAY 0.489362 (-2850 5950);
PAINT GREEN (-2850 5950);
FORCEPROP 2 LAST CDS_LIB pure_quanta_power
J 0
(-2825 5900);
DISPLAY INVISIBLE (-2825 5900);
FORCEPROP 2 LAST BOM_COST VR_SYSTEM
J 0
(-2825 6000);
DISPLAY 0.617021 (-2825 6000);
PAINT PURPLE (-2825 6000);
DISPLAY INVISIBLE (-2825 6000);
FORCEPROP 1 LAST PATH I371
J 0
(-2775 5925);
DISPLAY 0.872340 (-2775 5925);
PAINT AQUA (-2775 5925);
DISPLAY INVISIBLE (-2775 5925);
FORCEADD Q_RES..1
(-7975 2775);
FORCEPROP 1 LAST LOCATION R1569
J 0
(-8025 2800);
DISPLAY 0.510638 (-8025 2800);
PAINT SKYBLUE (-8025 2800);
FORCEPROP 0 LAST $SEC 1
J 0
(-8025 2875);
DISPLAY 0.680851 (-8025 2875);
PAINT MONO (-8025 2875);
DISPLAY INVISIBLE (-8025 2875);
FORCEPROP 0 LAST CDS_SEC 1
J 0
(-8025 2875);
DISPLAY 0.680851 (-8025 2875);
DISPLAY INVISIBLE (-8025 2875);
FORCEPROP 1 LASTPIN (-8075 2775) $PN 1
J 0
(-8063 2787);
DISPLAY 0.787234 (-8063 2787);
PAINT MONO (-8063 2787);
FORCEPROP 1 LASTPIN (-7875 2775) $PN 2
J 0
(-7913 2787);
DISPLAY 0.787234 (-7913 2787);
PAINT MONO (-7913 2787);
FORCEPROP 1 LAST VALUE 49.9
J 2
(-7850 2850);
DISPLAY 0.510638 (-7850 2850);
PAINT SKYBLUE (-7850 2850);
FORCEPROP 1 LAST TOLERANCE 1%
J 0
(-7975 2675);
DISPLAY 0.978723 (-7975 2675);
DISPLAY INVISIBLE (-7975 2675);
FORCEPROP 1 LAST WATTAGE 1/16W
J 2
(-8000 2625);
DISPLAY 0.978723 (-8000 2625);
DISPLAY INVISIBLE (-8000 2625);
FORCEPROP 1 LAST PACK_TYPE 0402LF
J 0
(-7725 2625);
DISPLAY 0.978723 (-7725 2625);
DISPLAY INVISIBLE (-7725 2625);
FORCEPROP 1 LAST MATERIAL CHIP
J 0
(-7975 2625);
DISPLAY 0.978723 (-7975 2625);
DISPLAY INVISIBLE (-7975 2625);
FORCEPROP 2 LAST CDS_LIB pure_quanta
J 0
(-7975 2775);
DISPLAY INVISIBLE (-7975 2775);
FORCEPROP 1 LAST PATH I372
J 0
(-8025 2925);
DISPLAY 0.978723 (-8025 2925);
PAINT WHITE (-8025 2925);
DISPLAY INVISIBLE (-8025 2925);
FORCEPROP 1 LAST PART_NUMBER CS04992FB07
J 0
(-8025 2875);
DISPLAY 0.978723 (-8025 2875);
DISPLAY INVISIBLE (-8025 2875);
FORCEADD Q_RES..1
(-8300 2975);
FORCEPROP 1 LAST LOCATION R1675
J 0
(-8475 2975);
DISPLAY 0.510638 (-8475 2975);
FORCEPROP 2 LAST SEC 1
J 0
(-8350 3175);
DISPLAY 0.680851 (-8350 3175);
PAINT MONO (-8350 3175);
DISPLAY INVISIBLE (-8350 3175);
FORCEPROP 1 LASTPIN (-8400 2975) $PN 1
J 0
(-8385 2985);
DISPLAY 0.510638 (-8385 2985);
PAINT MONO (-8385 2985);
FORCEPROP 1 LASTPIN (-8200 2975) $PN 2
J 0
(-8235 2985);
DISPLAY 0.510638 (-8235 2985);
PAINT MONO (-8235 2985);
FORCEPROP 1 LAST PACK_TYPE 0402LF
J 0
(-8250 2950);
DISPLAY 0.404255 (-8250 2950);
FORCEPROP 1 LAST MATERIAL CHIP
J 0
(-8350 2925);
DISPLAY 0.404255 (-8350 2925);
FORCEPROP 1 LAST VALUE 10
J 2
(-8150 2975);
DISPLAY 0.404255 (-8150 2975);
FORCEPROP 1 LAST TOLERANCE 1%
J 0
(-8300 2875);
DISPLAY 0.978723 (-8300 2875);
DISPLAY INVISIBLE (-8300 2875);
FORCEPROP 1 LAST WATTAGE 1/16W
J 2
(-8325 2825);
DISPLAY 0.978723 (-8325 2825);
DISPLAY INVISIBLE (-8325 2825);
FORCEPROP 2 LAST CDS_LIB pure_quanta
J 0
(-8300 2975);
DISPLAY INVISIBLE (-8300 2975);
FORCEPROP 2 LAST SEC_TYPE 0402LF
J 0
(-8350 3175);
DISPLAY 0.680851 (-8350 3175);
DISPLAY INVISIBLE (-8350 3175);
FORCEPROP 1 LAST PATH I373
J 0
(-8350 3125);
DISPLAY 0.978723 (-8350 3125);
PAINT WHITE (-8350 3125);
DISPLAY INVISIBLE (-8350 3125);
FORCEPROP 1 LAST PART_NUMBER CS01002FB07
J 0
(-8350 3075);
DISPLAY 0.978723 (-8350 3075);
DISPLAY INVISIBLE (-8350 3075);
FORCEADD OFFPAGE..6
(-8975 2900);
FORCEPROP 2 LAST $XR5 159 
J 0
(-9434 2864);
DISPLAY 0.638298 (-9434 2864);
PAINT MONO (-9434 2864);
FORCEPROP 2 LAST $XR4 91 
J 0
(-9314 2864);
DISPLAY 0.638298 (-9314 2864);
PAINT MONO (-9314 2864);
FORCEPROP 2 LAST $XR3 90 
J 0
(-9224 2864);
DISPLAY 0.638298 (-9224 2864);
PAINT MONO (-9224 2864);
FORCEPROP 2 LAST $XR2 89 
J 0
(-9404 2900);
DISPLAY 0.638298 (-9404 2900);
PAINT MONO (-9404 2900);
FORCEPROP 2 LAST $XR1 88 
J 0
(-9314 2900);
DISPLAY 0.638298 (-9314 2900);
PAINT MONO (-9314 2900);
FORCEPROP 2 LAST $XR0 86 
J 0
(-9224 2900);
DISPLAY 0.638298 (-9224 2900);
PAINT MONO (-9224 2900);
FORCEPROP 2 LAST CDS_LIB mstr_standard
J 0
(-8975 2900);
DISPLAY 0.808511 (-8975 2900);
DISPLAY INVISIBLE (-8975 2900);
FORCEPROP 1 LAST OFFPAGE TRUE
J 0
(-8650 2775);
DISPLAY 0.872340 (-8650 2775);
PAINT GREEN (-8650 2775);
DISPLAY INVISIBLE (-8650 2775);
FORCEPROP 1 LAST COMMENT_BODY TRUE
J 0
(-8875 2825);
DISPLAY 0.872340 (-8875 2825);
PAINT GREEN (-8875 2825);
DISPLAY INVISIBLE (-8875 2825);
FORCEPROP 2 LAST PATH I374
J 0
(-9200 2950);
DISPLAY 0.680851 (-9200 2950);
DISPLAY INVISIBLE (-9200 2950);
FORCEADD DNS..2
(-8525 2425);
PAINT RED (-8525 2425);
FORCEPROP 2 LAST CDS_LIB mstr_misc
J 0
(-8525 2425);
DISPLAY INVISIBLE (-8525 2425);
FORCEPROP 1 LAST COMMENT_BODY TRUE
R 1
J 0
(-8450 2200);
DISPLAY 0.872340 (-8450 2200);
PAINT PEACH (-8450 2200);
DISPLAY INVISIBLE (-8450 2200);
FORCEADD QUANTA_TITLE_BLOCK_C..1
(-100 100);
FORCEPROP 0 LAST CDS_CON_LAST_MODIFIED Thu Sep 14 16:12:05 2023
J 0
(-1985 115);
DISPLAY INVISIBLE (-1985 115);
FORCEPROP 1 LAST CUSTOM_TXT_CDS <CON_LAST_MODIFIED>
J 0
(-1985 115);
DISPLAY 0.978723 (-1985 115);
FORCEPROP 2 LAST CUSTOM_TXT_CDS <XR_PAGE_TITLE>
J 0
(-7990 5350);
DISPLAY 0.638298 (-7990 5350);
PAINT PINK (-7990 5350);
DISPLAY INVISIBLE (-7990 5350);
FORCEPROP 1 LAST CUSTOM_TXT_CDS <NAME_2>
J 0
(-3275 150);
FORCEPROP 1 LAST CUSTOM_TXT_CDS <NAME_1>
J 0
(-3275 275);
FORCEPROP 1 LAST CUSTOM_TXT_CDS <Q_NUMBER>
J 0
(-1503 203);
DISPLAY 1.212766 (-1503 203);
FORCEPROP 1 LAST CUSTOM_TXT_CDS <Q_PROJ>
J 0
(-2482 202);
DISPLAY 1.212766 (-2482 202);
FORCEPROP 1 LAST CUSTOM_TXT_CDS <Q_REV>
J 0
(-284 203);
DISPLAY 1.212766 (-284 203);
FORCEPROP 1 LAST CUSTOM_TXT_CDS <CON_PAGE_NUM> OF <CON_TOTAL_PAGES>
J 0
(-546 118);
DISPLAY 0.978723 (-546 118);
FORCEPROP 1 LAST Q_TITLE DDR5 - CPU0 CHB
J 0
(-9425 150);
DISPLAY 2.446809 (-9425 150);
PAINT GREEN (-9425 150);
FORCEPROP 2 LAST CDS_LIB pure_quanta
J 0
(-100 100);
DISPLAY INVISIBLE (-100 100);
FORCEPROP 1 LAST CDS_LMAN_SYM_OUTLINE -9475,6775,100,-125
J 0
(-100 100);
DISPLAY 0.468085 (-100 100);
PAINT GREEN (-100 100);
DISPLAY INVISIBLE (-100 100);
FORCEPROP 2 LAST PAGE_BORDER TRUE
J 0
(-7990 5350);
DISPLAY 0.638298 (-7990 5350);
PAINT PINK (-7990 5350);
DISPLAY INVISIBLE (-7990 5350);
FORCEPROP 2 LAST CDS_XR_PAGE_TITLE CR-87 : @T6G_MB_LIB.T6G(SCH_1):PAGE87
J 0
(-7990 5350);
DISPLAY 0.638298 (-7990 5350);
PAINT PINK (-7990 5350);
DISPLAY INVISIBLE (-7990 5350);
FORCEPROP 1 LAST Q_DEPT BU9
J 1
(-3863 149);
DISPLAY 1.957447 (-3863 149);
PAINT GREEN (-3863 149);
DISPLAY INVISIBLE (-3863 149);
FORCEPROP 1 LAST COMMENT_BODY TRUE
J 0
(-88 87);
DISPLAY 0.978723 (-88 87);
PAINT GREEN (-88 87);
DISPLAY INVISIBLE (-88 87);
WIRE 17 -1 (-8000 3600)(-8000 3650);
WIRE 17 -1 (-8000 3600)(-8000 3550);
WIRE 17 -1 (-8000 3700)(-8000 3650);
WIRE 17 -1 (-8000 3700)(-8000 3725);
WIRE 17 -1 (-8000 3500)(-8000 3550);
WIRE 17 -1 (-8000 3450)(-8000 3500);
WIRE 17 -1 (-8000 3725)(-8500 3725);
FORCEPROP 2 LAST SIG_NAME M_B_CPU0_SB_CB<7:0>
J 0
(-8450 3735);
DISPLAY 0.489362 (-8450 3735);
WIRE 17 -1 (-8000 3400)(-8000 3450);
WIRE 17 -1 (-8000 3350)(-8000 3400);
WIRE 17 -1 (-6200 2600)(-6200 2550);
WIRE 17 -1 (-6200 2650)(-6200 2600);
WIRE 17 -1 (-6200 2500)(-6200 2550);
WIRE 17 -1 (-6200 2450)(-6200 2500);
WIRE 17 -1 (-6200 2700)(-6200 2650);
WIRE 17 -1 (-6200 2750)(-6200 2700);
WIRE 17 -1 (-6200 2400)(-6200 2450);
WIRE 17 -1 (-6200 2350)(-6200 2400);
WIRE 17 -1 (-6200 2800)(-6200 2750);
WIRE 17 -1 (-6200 2850)(-6200 2800);
WIRE 17 -1 (-6200 2900)(-6200 2850);
WIRE 17 -1 (-6200 2950)(-6200 2900);
WIRE 17 -1 (-6200 2950)(-6200 3000);
WIRE 17 -1 (-6200 3000)(-6200 3050);
WIRE 17 -1 (-6200 3050)(-6200 3100);
WIRE 17 -1 (-6200 3100)(-6200 3150);
WIRE 17 -1 (-6200 3200)(-6200 3150);
WIRE 17 -1 (-6200 3250)(-6200 3200);
WIRE 17 -1 (-6200 3300)(-6200 3250);
WIRE 17 -1 (-6200 3350)(-6200 3300);
WIRE 17 -1 (-6200 3400)(-6200 3350);
WIRE 17 -1 (-6200 3450)(-6200 3400);
WIRE 17 -1 (-6200 3500)(-6200 3450);
WIRE 17 -1 (-6200 3550)(-6200 3500);
WIRE 17 -1 (-6200 3600)(-6200 3550);
WIRE 17 -1 (-6200 3650)(-6200 3600);
WIRE 17 -1 (-6200 3700)(-6200 3650);
WIRE 17 -1 (-6200 3750)(-6200 3700);
WIRE 17 -1 (-6200 3800)(-6200 3750);
WIRE 17 -1 (-6200 3850)(-6200 3800);
WIRE 17 -1 (-6200 3900)(-6200 3850);
WIRE 17 -1 (-6200 3925)(-6200 3900);
WIRE 17 -1 (-6200 3925)(-5550 3925);
FORCEPROP 2 LAST SIG_NAME M_B_CPU0_SB_DQ<31:0>
J 0
(-6135 3935);
DISPLAY 0.489362 (-6135 3935);
WIRE 17 -1 (-6200 5575)(-6200 5550);
WIRE 17 -1 (-6200 5575)(-5550 5575);
FORCEPROP 2 LAST SIG_NAME M_B_CPU0_SA_DQ<31:0>
J 0
(-6135 5585);
DISPLAY 0.489362 (-6135 5585);
WIRE 17 -1 (-8000 4150)(-8000 4175);
WIRE 17 -1 (-8000 4150)(-8000 4100);
WIRE 17 -1 (-8000 4175)(-8500 4175);
FORCEPROP 2 LAST SIG_NAME M_B_CPU0_SA_CB<7:0>
J 0
(-8450 4185);
DISPLAY 0.489362 (-8450 4185);
WIRE 17 -1 (-8000 4050)(-8000 4000);
WIRE 17 -1 (-8000 4050)(-8000 4100);
WIRE 17 -1 (-8000 3950)(-8000 4000);
WIRE 17 -1 (-8000 3900)(-8000 3950);
WIRE 17 -1 (-8000 3850)(-8000 3900);
WIRE 17 -1 (-8000 3800)(-8000 3850);
WIRE 17 -1 (-8000 5250)(-8000 5300);
WIRE 17 -1 (-8000 5300)(-8000 5350);
WIRE 17 -1 (-8000 5350)(-8000 5400);
WIRE 17 -1 (-8000 5400)(-8000 5450);
WIRE 17 -1 (-8000 5450)(-8000 5500);
WIRE 17 -1 (-8000 5500)(-8000 5550);
WIRE 17 -1 (-8000 5550)(-8000 5575);
WIRE 17 -1 (-8000 5575)(-8500 5575);
FORCEPROP 2 LAST SIG_NAME M_B_CPU0_SA_CA<6:0>
J 0
(-8485 5585);
DISPLAY 0.489362 (-8485 5585);
WIRE 17 -1 (-8000 4850)(-8000 4900);
WIRE 17 -1 (-8000 4900)(-8000 4950);
WIRE 17 -1 (-8000 4950)(-8000 5000);
WIRE 17 -1 (-8000 5000)(-8000 5050);
WIRE 17 -1 (-8000 5050)(-8000 5100);
WIRE 17 -1 (-8000 5100)(-8000 5150);
WIRE 17 -1 (-8000 5150)(-8000 5175);
WIRE 17 -1 (-8000 5175)(-8500 5175);
FORCEPROP 2 LAST SIG_NAME M_B_CPU0_SB_CA<6:0>
J 0
(-8485 5185);
DISPLAY 0.489362 (-8485 5185);
WIRE 17 -1 (-6200 5550)(-6200 5500);
WIRE 17 -1 (-6200 5500)(-6200 5450);
WIRE 17 -1 (-6200 5450)(-6200 5400);
WIRE 17 -1 (-6200 5400)(-6200 5350);
WIRE 17 -1 (-6200 5250)(-6200 5200);
WIRE 17 -1 (-6200 5300)(-6200 5250);
WIRE 17 -1 (-6200 5200)(-6200 5150);
WIRE 17 -1 (-6200 5150)(-6200 5100);
WIRE 17 -1 (-6200 5350)(-6200 5300);
WIRE 17 -1 (-6200 5100)(-6200 5050);
WIRE 17 -1 (-6200 5050)(-6200 5000);
WIRE 17 -1 (-6200 5000)(-6200 4950);
WIRE 17 -1 (-6200 4950)(-6200 4900);
WIRE 17 -1 (-6200 4900)(-6200 4850);
WIRE 17 -1 (-6200 4850)(-6200 4800);
WIRE 17 -1 (-6200 4750)(-6200 4800);
WIRE 17 -1 (-6200 4700)(-6200 4750);
WIRE 17 -1 (-6200 4650)(-6200 4700);
WIRE 17 -1 (-6200 4600)(-6200 4650);
WIRE 17 -1 (-6200 4600)(-6200 4550);
WIRE 17 -1 (-6200 4550)(-6200 4500);
WIRE 17 -1 (-6200 4500)(-6200 4450);
WIRE 17 -1 (-6200 4450)(-6200 4400);
WIRE 17 -1 (-6200 4400)(-6200 4350);
WIRE 17 -1 (-6200 4350)(-6200 4300);
WIRE 17 -1 (-6200 4300)(-6200 4250);
WIRE 17 -1 (-6200 4250)(-6200 4200);
WIRE 17 -1 (-6200 4150)(-6200 4200);
WIRE 17 -1 (-6200 4100)(-6200 4150);
WIRE 17 -1 (-6200 4050)(-6200 4100);
WIRE 17 -1 (-6200 4000)(-6200 4050);
WIRE 17 -1 (-3400 4525)(-3400 4425);
WIRE 17 -1 (-3400 4625)(-3400 4525);
WIRE 17 -1 (-3400 4425)(-3400 4325);
WIRE 17 -1 (-3400 4325)(-3400 4225);
WIRE 17 -1 (-3400 4650)(-3400 4625);
WIRE 17 -1 (-3400 4650)(-2700 4650);
FORCEPROP 2 LAST SIG_NAME M_B_CPU0_SA_DQS_DN<9:0>
J 0
(-3335 4660);
DISPLAY 0.489362 (-3335 4660);
WIRE 17 -1 (-3600 4475)(-3600 4375);
WIRE 17 -1 (-3600 4575)(-3600 4475);
WIRE 17 -1 (-3600 4375)(-3600 4275);
WIRE 17 -1 (-3600 4175)(-3600 4275);
WIRE 17 -1 (-3600 4675)(-3600 4575);
WIRE 17 -1 (-3600 4700)(-3600 4675);
WIRE 17 -1 (-3600 4075)(-3600 4175);
WIRE 17 -1 (-3600 3975)(-3600 4075);
WIRE 17 -1 (-3600 4700)(-2700 4700);
FORCEPROP 2 LAST SIG_NAME M_B_CPU0_SA_DQS_DP<9:0>
J 0
(-3335 4710);
DISPLAY 0.489362 (-3335 4710);
WIRE 17 -1 (-3600 3625)(-3600 3525);
WIRE 17 -1 (-3600 3650)(-3600 3625);
WIRE 17 -1 (-3600 3525)(-3600 3425);
WIRE 17 -1 (-3600 3425)(-3600 3325);
WIRE 17 -1 (-3600 3650)(-2700 3650);
FORCEPROP 2 LAST SIG_NAME M_B_CPU0_SB_DQS_DP<9:0>
J 0
(-3335 3660);
DISPLAY 0.489362 (-3335 3660);
WIRE 17 -1 (-3400 3575)(-3400 3475);
WIRE 17 -1 (-3400 3600)(-3400 3575);
WIRE 17 -1 (-3400 3475)(-3400 3375);
WIRE 17 -1 (-3400 3375)(-3400 3275);
WIRE 17 -1 (-3400 3600)(-2700 3600);
FORCEPROP 2 LAST SIG_NAME M_B_CPU0_SB_DQS_DN<9:0>
J 0
(-3335 3610);
DISPLAY 0.489362 (-3335 3610);
WIRE 17 -1 (-3600 3325)(-3600 3225);
WIRE 17 -1 (-3400 2775)(-3400 2675);
WIRE 17 -1 (-3400 2875)(-3400 2775);
WIRE 17 -1 (-3400 2875)(-3400 2975);
WIRE 17 -1 (-3400 2975)(-3400 3075);
WIRE 17 -1 (-3400 3075)(-3400 3175);
WIRE 17 -1 (-3400 3275)(-3400 3175);
WIRE 17 -1 (-3600 2825)(-3600 2725);
WIRE 17 -1 (-3600 2925)(-3600 2825);
WIRE 17 -1 (-3600 2925)(-3600 3025);
WIRE 17 -1 (-3600 3025)(-3600 3125);
WIRE 17 -1 (-3600 3125)(-3600 3225);
WIRE 17 -1 (-3400 3925)(-3400 3825);
WIRE 17 -1 (-3400 3925)(-3400 4025);
WIRE 17 -1 (-3400 3825)(-3400 3725);
WIRE 17 -1 (-3400 4025)(-3400 4125);
WIRE 17 -1 (-3400 4125)(-3400 4225);
WIRE 17 -1 (-3600 3975)(-3600 3875);
WIRE 17 -1 (-3600 3875)(-3600 3775);
WIRE 16 -1 (-6650 1225)(-6650 1300);
WIRE 16 -1 (-9050 3150)(-9050 3225);
WIRE 16 -1 (-8550 2525)(-8550 2550);
WIRE 16 -1 (-8925 3075)(-7700 3075);
WIRE 16 -1 (-8925 3500)(-8925 3075);
WIRE 16 -1 (-8925 3525)(-8925 3500);
WIRE 16 -1 (-9050 3500)(-8925 3500);
WIRE 16 -1 (-9050 3425)(-9050 3500);
WIRE 16 -1 (-7700 2975)(-8200 2975);
FORCEPROP 2 LAST SIG_NAME I3C_SPD_DDRB_CPU0_SDA
J 0
(-8110 2985);
DISPLAY 0.361702 (-8110 2985);
FORCEPROP 2 LASTPROP $XRERR UNIQUE?
J 0
(-8350 2985);
DISPLAY 0.638298 (-8350 2985);
PAINT MONO (-8350 2985);
DISPLAY INVISIBLE (-8350 2985);
WIRE 16 -1 (-8075 2775)(-8525 2775);
FORCEPROP 2 LAST SIG_NAME I3C_SPD_DDRAF_CPU0_SCL
J 0
(-8560 2785);
DISPLAY 0.446809 (-8560 2785);
WIRE 16 -1 (-8350 2275)(-8350 2675);
WIRE 16 -1 (-8350 2275)(-8550 2275);
WIRE 16 -1 (-7700 2675)(-8350 2675);
FORCEPROP 2 LAST SIG_NAME PWRGD_CHB_CPU0_DIMM
J 0
(-8275 2685);
DISPLAY 0.489362 (-8275 2685);
FORCEPROP 2 LASTPROP $XRERR UNIQUE?
J 0
(-8515 2685);
DISPLAY 0.638298 (-8515 2685);
PAINT MONO (-8515 2685);
DISPLAY INVISIBLE (-8515 2685);
WIRE 16 -1 (-8550 2325)(-8550 2275);
WIRE 16 -1 (-8550 2275)(-8575 2275);
WIRE 16 -1 (-7700 3025)(-8500 3025);
FORCEPROP 2 LAST SIG_NAME PD_CHB_CPU0_DIMM_SAA
J 0
(-8475 3035);
DISPLAY 0.489362 (-8475 3035);
WIRE 16 -1 (-7700 3475)(-7900 3475);
WIRE 16 -1 (-7700 3325)(-7900 3325);
WIRE 16 -1 (-7700 3375)(-7900 3375);
WIRE 16 -1 (-7700 3425)(-7900 3425);
WIRE 16 -1 (-6300 3525)(-6500 3525);
WIRE 16 -1 (-6300 3825)(-6500 3825);
WIRE 16 -1 (-7700 4275)(-8500 4275);
FORCEPROP 2 LAST SIG_NAME M_B_CPU0_CLK_DP<0>
J 0
(-8450 4285);
DISPLAY 0.489362 (-8450 4285);
WIRE 16 -1 (-7700 4375)(-8500 4375);
FORCEPROP 2 LAST SIG_NAME M_B_CPU0_SB_CS_N<0>
J 0
(-8450 4385);
DISPLAY 0.489362 (-8450 4385);
WIRE 16 -1 (-7700 4725)(-8500 4725);
FORCEPROP 2 LAST SIG_NAME M_B_CPU0_SA_PAR
J 0
(-8450 4735);
DISPLAY 0.489362 (-8450 4735);
WIRE 16 -1 (-7700 4675)(-8500 4675);
FORCEPROP 2 LAST SIG_NAME M_B_CPU0_SB_PAR
J 0
(-8450 4685);
DISPLAY 0.489362 (-8450 4685);
WIRE 16 -1 (-6300 5275)(-6500 5275);
WIRE 16 -1 (-6300 5225)(-6500 5225);
WIRE 16 -1 (-3850 3600)(-3700 3600);
WIRE 16 -1 (-3500 3550)(-3850 3550);
WIRE 16 -1 (-3850 3700)(-3500 3700);
WIRE 16 -1 (-3700 3750)(-3850 3750);
WIRE 16 -1 (-3850 4650)(-3700 4650);
WIRE 16 -1 (-3500 4600)(-3850 4600);
WIRE 16 -1 (-3700 4550)(-3850 4550);
WIRE 16 -1 (-3500 4500)(-3850 4500);
WIRE 16 -1 (-3500 3350)(-3850 3350);
WIRE 16 -1 (-3700 4450)(-3850 4450);
WIRE 16 -1 (-3700 3300)(-3850 3300);
WIRE 16 -1 (-3500 3250)(-3850 3250);
WIRE 16 -1 (-3500 4300)(-3850 4300);
WIRE 16 -1 (-3850 3200)(-3700 3200);
WIRE 16 -1 (-3500 3150)(-3850 3150);
WIRE 16 -1 (-3850 4250)(-3700 4250);
WIRE 16 -1 (-3500 4200)(-3850 4200);
WIRE 16 -1 (-3700 3100)(-3850 3100);
WIRE 16 -1 (-3500 3050)(-3850 3050);
WIRE 16 -1 (-3700 4150)(-3850 4150);
WIRE 16 -1 (-3500 4100)(-3850 4100);
WIRE 16 -1 (-3700 3000)(-3850 3000);
WIRE 16 -1 (-3500 2950)(-3850 2950);
WIRE 16 -1 (-3700 4050)(-3850 4050);
WIRE 16 -1 (-3500 4000)(-3850 4000);
WIRE 16 -1 (-3700 2900)(-3850 2900);
WIRE 16 -1 (-3500 2850)(-3850 2850);
WIRE 16 -1 (-3700 3950)(-3850 3950);
WIRE 16 -1 (-3500 3900)(-3850 3900);
WIRE 16 -1 (-3850 2800)(-3700 2800);
WIRE 16 -1 (-3500 2750)(-3850 2750);
WIRE 16 -1 (-3850 3850)(-3700 3850);
WIRE 16 -1 (-3500 3800)(-3850 3800);
WIRE 16 -1 (-3700 2700)(-3850 2700);
WIRE 16 -1 (-3850 2650)(-3500 2650);
WIRE 16 -1 (-3700 3400)(-3850 3400);
WIRE 16 -1 (-3500 3450)(-3850 3450);
WIRE 16 -1 (-3700 3500)(-3850 3500);
WIRE 16 -1 (-3700 4350)(-3850 4350);
WIRE 16 -1 (-3500 4400)(-3850 4400);
WIRE 16 -1 (-6500 5325)(-6300 5325);
WIRE 16 -1 (-6300 5375)(-6500 5375);
WIRE 16 -1 (-7700 5525)(-7900 5525);
WIRE 16 -1 (-6500 4925)(-6300 4925);
WIRE 16 -1 (-6300 4875)(-6500 4875);
WIRE 16 -1 (-7700 2125)(-8500 2125);
FORCEPROP 2 LAST SIG_NAME M_B_CPU0_SA_RSP<0>
J 0
(-8450 2135);
DISPLAY 0.489362 (-8450 2135);
WIRE 16 -1 (-6300 2325)(-6500 2325);
WIRE 16 -1 (-6300 2375)(-6500 2375);
WIRE 16 -1 (-6300 2425)(-6500 2425);
WIRE 16 -1 (-6500 2475)(-6300 2475);
WIRE 16 -1 (-6300 2575)(-6500 2575);
WIRE 16 -1 (-6300 2625)(-6500 2625);
WIRE 16 -1 (-6500 2675)(-6300 2675);
WIRE 16 -1 (-6300 2725)(-6500 2725);
WIRE 16 -1 (-6300 2775)(-6500 2775);
WIRE 16 -1 (-6300 2825)(-6500 2825);
WIRE 16 -1 (-6500 2875)(-6300 2875);
WIRE 16 -1 (-6300 2925)(-6500 2925);
WIRE 16 -1 (-6300 2975)(-6500 2975);
WIRE 16 -1 (-6300 3025)(-6500 3025);
WIRE 16 -1 (-6500 3075)(-6300 3075);
WIRE 16 -1 (-6300 3125)(-6500 3125);
WIRE 16 -1 (-6300 3175)(-6500 3175);
WIRE 16 -1 (-6300 3225)(-6500 3225);
WIRE 16 -1 (-6500 3275)(-6300 3275);
WIRE 16 -1 (-6300 3325)(-6500 3325);
WIRE 16 -1 (-6300 3375)(-6500 3375);
WIRE 16 -1 (-6300 3425)(-6500 3425);
WIRE 16 -1 (-6500 3475)(-6300 3475);
WIRE 16 -1 (-6300 3575)(-6500 3575);
WIRE 16 -1 (-6300 3625)(-6500 3625);
WIRE 16 -1 (-6500 3675)(-6300 3675);
WIRE 16 -1 (-6300 3725)(-6500 3725);
WIRE 16 -1 (-6300 3775)(-6500 3775);
WIRE 16 -1 (-6500 3875)(-6300 3875);
WIRE 16 -1 (-6300 3975)(-6500 3975);
WIRE 16 -1 (-6300 4025)(-6500 4025);
WIRE 16 -1 (-6300 4075)(-6500 4075);
WIRE 16 -1 (-6500 4125)(-6300 4125);
WIRE 16 -1 (-6300 4175)(-6500 4175);
WIRE 16 -1 (-6300 4225)(-6500 4225);
WIRE 16 -1 (-6300 4275)(-6500 4275);
WIRE 16 -1 (-6500 4325)(-6300 4325);
WIRE 16 -1 (-6300 4375)(-6500 4375);
WIRE 16 -1 (-6300 4425)(-6500 4425);
WIRE 16 -1 (-6300 4475)(-6500 4475);
WIRE 16 -1 (-6500 4525)(-6300 4525);
WIRE 16 -1 (-6300 4575)(-6500 4575);
WIRE 16 -1 (-6300 4625)(-6500 4625);
WIRE 16 -1 (-6300 4675)(-6500 4675);
WIRE 16 -1 (-6500 4725)(-6300 4725);
WIRE 16 -1 (-6300 4775)(-6500 4775);
WIRE 16 -1 (-6300 4825)(-6500 4825);
WIRE 16 -1 (-6300 4975)(-6500 4975);
WIRE 16 -1 (-6300 5025)(-6500 5025);
WIRE 16 -1 (-6300 5075)(-6500 5075);
WIRE 16 -1 (-6500 5125)(-6300 5125);
WIRE 16 -1 (-6300 5175)(-6500 5175);
WIRE 16 -1 (-6300 5425)(-6500 5425);
WIRE 16 -1 (-6300 5475)(-6500 5475);
WIRE 16 -1 (-7700 4425)(-8500 4425);
FORCEPROP 2 LAST SIG_NAME M_B_CPU0_SB_CS_N<1>
J 0
(-8450 4435);
DISPLAY 0.489362 (-8450 4435);
WIRE 16 -1 (-7700 4575)(-8500 4575);
FORCEPROP 2 LAST SIG_NAME M_B_CPU0_SA_CS_N<1>
J 0
(-8450 4585);
DISPLAY 0.489362 (-8450 4585);
WIRE 16 -1 (-7700 4525)(-8500 4525);
FORCEPROP 2 LAST SIG_NAME M_B_CPU0_SA_CS_N<0>
J 0
(-8450 4535);
DISPLAY 0.489362 (-8450 4535);
WIRE 16 -1 (-7700 4225)(-8500 4225);
FORCEPROP 2 LAST SIG_NAME M_B_CPU0_CLK_DN<0>
J 0
(-8450 4235);
DISPLAY 0.489362 (-8450 4235);
WIRE 16 -1 (-7700 3625)(-7900 3625);
WIRE 16 -1 (-7700 3775)(-7900 3775);
WIRE 16 -1 (-7700 3875)(-7900 3875);
WIRE 16 -1 (-7700 3925)(-7900 3925);
WIRE 16 -1 (-7700 4025)(-7900 4025);
WIRE 16 -1 (-7700 4075)(-7900 4075);
WIRE 16 -1 (-7700 5125)(-7900 5125);
WIRE 16 -1 (-7700 5075)(-7900 5075);
WIRE 16 -1 (-7700 5475)(-7900 5475);
WIRE 16 -1 (-7700 5025)(-7900 5025);
WIRE 16 -1 (-7700 5425)(-7900 5425);
WIRE 16 -1 (-7700 4975)(-7900 4975);
WIRE 16 -1 (-7700 5375)(-7900 5375);
WIRE 16 -1 (-7700 4925)(-7900 4925);
WIRE 16 -1 (-7700 5325)(-7900 5325);
WIRE 16 -1 (-7700 4875)(-7900 4875);
WIRE 16 -1 (-7700 5275)(-7900 5275);
WIRE 16 -1 (-7700 4825)(-7900 4825);
WIRE 16 -1 (-7700 5225)(-7900 5225);
WIRE 16 -1 (-7700 3675)(-7900 3675);
WIRE 16 -1 (-7700 3825)(-7900 3825);
WIRE 16 -1 (-7700 3975)(-7900 3975);
WIRE 16 -1 (-7700 4125)(-7900 4125);
WIRE 16 -1 (-6500 5525)(-6300 5525);
WIRE 16 -1 (-6650 1575)(-6650 1500);
WIRE 16 -1 (-6650 1575)(-7375 1575);
FORCEPROP 2 LAST SIG_NAME PD_CHB_CPU0_DIMM_SAA
J 0
(-7360 1585);
DISPLAY 0.489362 (-7360 1585);
WIRE 16 -1 (-7700 2075)(-8500 2075);
FORCEPROP 2 LAST SIG_NAME M_B_CPU0_SB_RSP<0>
J 0
(-8450 2085);
DISPLAY 0.489362 (-8450 2085);
WIRE 16 -1 (-6300 2525)(-6500 2525);
WIRE 16 -1 (-9125 2275)(-8775 2275);
FORCEPROP 2 LAST SIG_NAME PWRGD_CHAF_CPU0
J 0
(-9135 2285);
DISPLAY 0.489362 (-9135 2285);
WIRE 16 -1 (-1825 2025)(-2125 2025);
WIRE 16 -1 (-2125 2075)(-2125 2025);
WIRE 16 -1 (-2125 2025)(-2125 1975);
WIRE 16 -1 (-1825 1975)(-2125 1975);
WIRE 16 -1 (-2125 1975)(-2125 1875);
WIRE 16 -1 (-1825 2075)(-2125 2075);
WIRE 16 -1 (-2125 2125)(-2125 2075);
WIRE 16 -1 (-1825 2125)(-2125 2125);
WIRE 16 -1 (-2125 2175)(-2125 2125);
WIRE 16 -1 (-1825 2175)(-2125 2175);
WIRE 16 -1 (-2125 2225)(-2125 2175);
WIRE 16 -1 (-1825 2225)(-2125 2225);
WIRE 16 -1 (-2125 2275)(-2125 2225);
WIRE 16 -1 (-1825 2275)(-2125 2275);
WIRE 16 -1 (-2125 2325)(-2125 2275);
WIRE 16 -1 (-1825 2325)(-2125 2325);
WIRE 16 -1 (-2125 2375)(-2125 2325);
WIRE 16 -1 (-1825 2375)(-2125 2375);
WIRE 16 -1 (-2125 2425)(-2125 2375);
WIRE 16 -1 (-1825 2425)(-2125 2425);
WIRE 16 -1 (-2125 2475)(-2125 2425);
WIRE 16 -1 (-1825 2475)(-2125 2475);
WIRE 16 -1 (-2125 2525)(-2125 2475);
WIRE 16 -1 (-1825 2525)(-2125 2525);
WIRE 16 -1 (-2125 2575)(-2125 2525);
WIRE 16 -1 (-1825 2575)(-2125 2575);
WIRE 16 -1 (-2125 2625)(-2125 2575);
WIRE 16 -1 (-1825 2625)(-2125 2625);
WIRE 16 -1 (-2125 2675)(-2125 2625);
WIRE 16 -1 (-1825 2675)(-2125 2675);
WIRE 16 -1 (-2125 2725)(-2125 2675);
WIRE 16 -1 (-1825 2725)(-2125 2725);
WIRE 16 -1 (-2125 2775)(-2125 2725);
WIRE 16 -1 (-1825 2775)(-2125 2775);
WIRE 16 -1 (-2125 2825)(-2125 2775);
WIRE 16 -1 (-1825 2825)(-2125 2825);
WIRE 16 -1 (-2125 2875)(-2125 2825);
WIRE 16 -1 (-1825 2875)(-2125 2875);
WIRE 16 -1 (-2125 2925)(-2125 2875);
WIRE 16 -1 (-1825 2925)(-2125 2925);
WIRE 16 -1 (-2125 2975)(-2125 2925);
WIRE 16 -1 (-1825 2975)(-2125 2975);
WIRE 16 -1 (-2125 3025)(-2125 2975);
WIRE 16 -1 (-1825 3025)(-2125 3025);
WIRE 16 -1 (-2125 3075)(-2125 3025);
WIRE 16 -1 (-1825 3075)(-2125 3075);
WIRE 16 -1 (-2125 3125)(-2125 3075);
WIRE 16 -1 (-1825 3125)(-2125 3125);
WIRE 16 -1 (-2125 3175)(-2125 3125);
WIRE 16 -1 (-1825 3175)(-2125 3175);
WIRE 16 -1 (-2125 3225)(-2125 3175);
WIRE 16 -1 (-1825 3225)(-2125 3225);
WIRE 16 -1 (-2125 3275)(-2125 3225);
WIRE 16 -1 (-1825 3275)(-2125 3275);
WIRE 16 -1 (-2125 3325)(-2125 3275);
WIRE 16 -1 (-1825 3325)(-2125 3325);
WIRE 16 -1 (-2125 3375)(-2125 3325);
WIRE 16 -1 (-1825 3375)(-2125 3375);
WIRE 16 -1 (-2125 3425)(-2125 3375);
WIRE 16 -1 (-1825 3425)(-2125 3425);
WIRE 16 -1 (-2125 3475)(-2125 3425);
WIRE 16 -1 (-1825 3475)(-2125 3475);
WIRE 16 -1 (-2125 3525)(-2125 3475);
WIRE 16 -1 (-1825 3525)(-2125 3525);
WIRE 16 -1 (-2125 3575)(-2125 3525);
WIRE 16 -1 (-1825 3575)(-2125 3575);
WIRE 16 -1 (-2125 3625)(-2125 3575);
WIRE 16 -1 (-1825 3625)(-2125 3625);
WIRE 16 -1 (-2125 3675)(-2125 3625);
WIRE 16 -1 (-1825 3675)(-2125 3675);
WIRE 16 -1 (-2125 3725)(-2125 3675);
WIRE 16 -1 (-1825 3725)(-2125 3725);
WIRE 16 -1 (-2125 3775)(-2125 3725);
WIRE 16 -1 (-1825 3775)(-2125 3775);
WIRE 16 -1 (-2125 3825)(-2125 3775);
WIRE 16 -1 (-1825 3825)(-2125 3825);
WIRE 16 -1 (-2125 3875)(-2125 3825);
WIRE 16 -1 (-1825 3875)(-2125 3875);
WIRE 16 -1 (-2125 3925)(-2125 3875);
WIRE 16 -1 (-1825 3925)(-2125 3925);
WIRE 16 -1 (-2125 3975)(-2125 3925);
WIRE 16 -1 (-1825 3975)(-2125 3975);
WIRE 16 -1 (-2125 4025)(-2125 3975);
WIRE 16 -1 (-1825 4025)(-2125 4025);
WIRE 16 -1 (-2125 4075)(-2125 4025);
WIRE 16 -1 (-2125 4125)(-2125 4075);
WIRE 16 -1 (-1825 4075)(-2125 4075);
WIRE 16 -1 (-1825 4125)(-2125 4125);
WIRE 16 -1 (-2125 4175)(-2125 4125);
WIRE 16 -1 (-1825 4175)(-2125 4175);
WIRE 16 -1 (-2125 4225)(-2125 4175);
WIRE 16 -1 (-1825 4225)(-2125 4225);
WIRE 16 -1 (-2125 4275)(-2125 4225);
WIRE 16 -1 (-1825 4275)(-2125 4275);
WIRE 16 -1 (-2125 4325)(-2125 4275);
WIRE 16 -1 (-1825 4325)(-2125 4325);
WIRE 16 -1 (-2125 4375)(-2125 4325);
WIRE 16 -1 (-1825 4375)(-2125 4375);
WIRE 16 -1 (-2125 4425)(-2125 4375);
WIRE 16 -1 (-1825 4425)(-2125 4425);
WIRE 16 -1 (-2125 4475)(-2125 4425);
WIRE 16 -1 (-1825 4475)(-2125 4475);
WIRE 16 -1 (-2125 4525)(-2125 4475);
WIRE 16 -1 (-1825 4525)(-2125 4525);
WIRE 16 -1 (-2125 4575)(-2125 4525);
WIRE 16 -1 (-1825 4575)(-2125 4575);
WIRE 16 -1 (-2125 4625)(-2125 4575);
WIRE 16 -1 (-1825 4625)(-2125 4625);
WIRE 16 -1 (-2125 4675)(-2125 4625);
WIRE 16 -1 (-1825 4675)(-2125 4675);
WIRE 16 -1 (-2125 4725)(-2125 4675);
WIRE 16 -1 (-1825 4725)(-2125 4725);
WIRE 16 -1 (-2125 4775)(-2125 4725);
WIRE 16 -1 (-1825 4775)(-2125 4775);
WIRE 16 -1 (-2125 4825)(-2125 4775);
WIRE 16 -1 (-1825 4825)(-2125 4825);
WIRE 16 -1 (-2125 4875)(-2125 4825);
WIRE 16 -1 (-1825 4875)(-2125 4875);
WIRE 16 -1 (-2125 4925)(-2125 4875);
WIRE 16 -1 (-1825 4925)(-2125 4925);
WIRE 16 -1 (-2125 4975)(-2125 4925);
WIRE 16 -1 (-1825 4975)(-2125 4975);
WIRE 16 -1 (-2125 5025)(-2125 4975);
WIRE 16 -1 (-1825 5025)(-2125 5025);
WIRE 16 -1 (-2125 5075)(-2125 5025);
WIRE 16 -1 (-1825 5075)(-2125 5075);
WIRE 16 -1 (-325 2075)(-325 1975);
WIRE 16 -1 (-325 2125)(-325 2075);
WIRE 16 -1 (-325 2075)(-625 2075);
WIRE 16 -1 (-325 1975)(-325 1925);
WIRE 16 -1 (-325 1975)(-625 1975);
WIRE 16 -1 (-325 1925)(-325 1875);
WIRE 16 -1 (-325 1925)(-625 1925);
WIRE 16 -1 (-325 2175)(-325 2125);
WIRE 16 -1 (-325 2125)(-625 2125);
WIRE 16 -1 (-325 2225)(-325 2175);
WIRE 16 -1 (-325 2175)(-625 2175);
WIRE 16 -1 (-325 1875)(-325 1700);
WIRE 16 -1 (-325 1875)(-625 1875);
WIRE 16 -1 (-325 2275)(-325 2225);
WIRE 16 -1 (-325 2225)(-625 2225);
WIRE 16 -1 (-325 2325)(-325 2275);
WIRE 16 -1 (-325 2275)(-625 2275);
WIRE 16 -1 (-325 2375)(-325 2325);
WIRE 16 -1 (-325 2325)(-625 2325);
WIRE 16 -1 (-325 2425)(-325 2375);
WIRE 16 -1 (-325 2375)(-625 2375);
WIRE 16 -1 (-325 2475)(-325 2425);
WIRE 16 -1 (-325 2425)(-625 2425);
WIRE 16 -1 (-325 2525)(-325 2475);
WIRE 16 -1 (-325 2475)(-625 2475);
WIRE 16 -1 (-325 2575)(-325 2525);
WIRE 16 -1 (-325 2525)(-625 2525);
WIRE 16 -1 (-325 2625)(-325 2575);
WIRE 16 -1 (-325 2575)(-625 2575);
WIRE 16 -1 (-325 2675)(-325 2625);
WIRE 16 -1 (-325 2625)(-625 2625);
WIRE 16 -1 (-325 2725)(-325 2675);
WIRE 16 -1 (-325 2675)(-625 2675);
WIRE 16 -1 (-325 2775)(-325 2725);
WIRE 16 -1 (-325 2725)(-625 2725);
WIRE 16 -1 (-325 2825)(-325 2775);
WIRE 16 -1 (-325 2775)(-625 2775);
WIRE 16 -1 (-325 2875)(-325 2825);
WIRE 16 -1 (-325 2825)(-625 2825);
WIRE 16 -1 (-325 2925)(-325 2875);
WIRE 16 -1 (-325 2875)(-625 2875);
WIRE 16 -1 (-325 2975)(-325 2925);
WIRE 16 -1 (-325 2925)(-625 2925);
WIRE 16 -1 (-325 3025)(-325 2975);
WIRE 16 -1 (-325 2975)(-625 2975);
WIRE 16 -1 (-325 3075)(-325 3025);
WIRE 16 -1 (-325 3025)(-625 3025);
WIRE 16 -1 (-325 3125)(-325 3075);
WIRE 16 -1 (-325 3075)(-625 3075);
WIRE 16 -1 (-325 3175)(-325 3125);
WIRE 16 -1 (-325 3125)(-625 3125);
WIRE 16 -1 (-325 3225)(-325 3175);
WIRE 16 -1 (-325 3175)(-625 3175);
WIRE 16 -1 (-325 3275)(-325 3225);
WIRE 16 -1 (-325 3225)(-625 3225);
WIRE 16 -1 (-325 3325)(-325 3275);
WIRE 16 -1 (-325 3275)(-625 3275);
WIRE 16 -1 (-325 3375)(-325 3325);
WIRE 16 -1 (-325 3325)(-625 3325);
WIRE 16 -1 (-325 3425)(-325 3375);
WIRE 16 -1 (-325 3375)(-625 3375);
WIRE 16 -1 (-325 3475)(-325 3425);
WIRE 16 -1 (-325 3425)(-625 3425);
WIRE 16 -1 (-325 3525)(-325 3475);
WIRE 16 -1 (-325 3475)(-625 3475);
WIRE 16 -1 (-325 3575)(-325 3525);
WIRE 16 -1 (-325 3525)(-625 3525);
WIRE 16 -1 (-325 3625)(-325 3575);
WIRE 16 -1 (-325 3575)(-625 3575);
WIRE 16 -1 (-325 3675)(-325 3625);
WIRE 16 -1 (-325 3625)(-625 3625);
WIRE 16 -1 (-325 3725)(-325 3675);
WIRE 16 -1 (-325 3675)(-625 3675);
WIRE 16 -1 (-325 3775)(-325 3725);
WIRE 16 -1 (-325 3725)(-625 3725);
WIRE 16 -1 (-325 3825)(-325 3775);
WIRE 16 -1 (-325 3775)(-625 3775);
WIRE 16 -1 (-325 3875)(-325 3825);
WIRE 16 -1 (-325 3825)(-625 3825);
WIRE 16 -1 (-325 3925)(-325 3875);
WIRE 16 -1 (-325 3875)(-625 3875);
WIRE 16 -1 (-325 3975)(-325 3925);
WIRE 16 -1 (-325 3925)(-625 3925);
WIRE 16 -1 (-325 4025)(-325 3975);
WIRE 16 -1 (-325 3975)(-625 3975);
WIRE 16 -1 (-325 4075)(-325 4025);
WIRE 16 -1 (-325 4025)(-625 4025);
WIRE 16 -1 (-325 4125)(-325 4075);
WIRE 16 -1 (-325 4075)(-625 4075);
WIRE 16 -1 (-325 4175)(-325 4125);
WIRE 16 -1 (-325 4125)(-625 4125);
WIRE 16 -1 (-325 4225)(-325 4175);
WIRE 16 -1 (-325 4175)(-625 4175);
WIRE 16 -1 (-325 4275)(-325 4225);
WIRE 16 -1 (-325 4225)(-625 4225);
WIRE 16 -1 (-325 4325)(-325 4275);
WIRE 16 -1 (-325 4275)(-625 4275);
WIRE 16 -1 (-325 4375)(-325 4325);
WIRE 16 -1 (-325 4325)(-625 4325);
WIRE 16 -1 (-325 4425)(-325 4375);
WIRE 16 -1 (-325 4375)(-625 4375);
WIRE 16 -1 (-325 4475)(-325 4425);
WIRE 16 -1 (-325 4425)(-625 4425);
WIRE 16 -1 (-325 4525)(-325 4475);
WIRE 16 -1 (-325 4475)(-625 4475);
WIRE 16 -1 (-325 4575)(-325 4525);
WIRE 16 -1 (-325 4525)(-625 4525);
WIRE 16 -1 (-325 4625)(-325 4575);
WIRE 16 -1 (-325 4575)(-625 4575);
WIRE 16 -1 (-325 4675)(-325 4625);
WIRE 16 -1 (-325 4625)(-625 4625);
WIRE 16 -1 (-325 4725)(-325 4675);
WIRE 16 -1 (-325 4675)(-625 4675);
WIRE 16 -1 (-325 4775)(-325 4725);
WIRE 16 -1 (-325 4725)(-625 4725);
WIRE 16 -1 (-325 4825)(-325 4775);
WIRE 16 -1 (-325 4775)(-625 4775);
WIRE 16 -1 (-325 4875)(-325 4825);
WIRE 16 -1 (-325 4825)(-625 4825);
WIRE 16 -1 (-325 4925)(-325 4875);
WIRE 16 -1 (-325 4875)(-625 4875);
WIRE 16 -1 (-325 4975)(-325 4925);
WIRE 16 -1 (-325 4925)(-625 4925);
WIRE 16 -1 (-325 5025)(-325 4975);
WIRE 16 -1 (-325 4975)(-625 4975);
WIRE 16 -1 (-325 5075)(-325 5025);
WIRE 16 -1 (-325 5025)(-625 5025);
WIRE 16 -1 (-325 5125)(-325 5075);
WIRE 16 -1 (-325 5075)(-625 5075);
WIRE 16 -1 (-325 5175)(-325 5125);
WIRE 16 -1 (-325 5125)(-625 5125);
WIRE 16 -1 (-325 5225)(-325 5175);
WIRE 16 -1 (-325 5175)(-625 5175);
WIRE 16 -1 (-325 5225)(-625 5225);
WIRE 16 -1 (-2250 5350)(-2250 5475);
WIRE 16 -1 (-2250 5350)(-2825 5350);
WIRE 16 -1 (-2825 5350)(-2825 5475);
WIRE 16 -1 (-2825 5350)(-2825 5275);
WIRE 16 -1 (-2250 5775)(-2250 5675);
WIRE 16 -1 (-2250 5775)(-2125 5775);
WIRE 16 -1 (-2250 5775)(-2825 5775);
WIRE 16 -1 (-2825 5675)(-2825 5775);
WIRE 16 -1 (-2825 5775)(-2825 5850);
WIRE 16 -1 (-2125 5225)(-2125 5775);
WIRE 16 -1 (-1825 5225)(-2125 5225);
WIRE 16 -1 (-2125 5175)(-2125 5225);
WIRE 16 -1 (-1825 5175)(-2125 5175);
WIRE 16 -1 (-2125 5125)(-2125 5175);
WIRE 16 -1 (-1825 5125)(-2125 5125);
WIRE 16 -1 (-7700 3525)(-7900 3525);
WIRE 16 -1 (-7700 3575)(-7900 3575);
WIRE 16 -1 (-7700 2925)(-7800 2925);
FORCEPROP 2 LAST SIG_NAME I3C_SPD_DDRB_CPU0_SCL
J 0
(-8160 2875);
DISPLAY 0.361702 (-8160 2875);
FORCEPROP 2 LASTPROP $XRERR UNIQUE?
J 0
(-8400 2875);
DISPLAY 0.638298 (-8400 2875);
PAINT MONO (-8400 2875);
DISPLAY INVISIBLE (-8400 2875);
WIRE 16 -1 (-7800 2925)(-7800 2775);
WIRE 16 -1 (-7800 2775)(-7875 2775);
WIRE 16 -1 (-8450 2975)(-8400 2975);
WIRE 16 -1 (-8450 2900)(-8450 2975);
WIRE 16 -1 (-8450 2900)(-8925 2900);
FORCEPROP 2 LAST SIG_NAME I3C_SPD_DDRAF_CPU0_SDA
J 0
(-8960 2910);
DISPLAY 0.489362 (-8960 2910);
WIRE 16 -1 (-7700 3225)(-8475 3225);
FORCEPROP 2 LAST SIG_NAME M_B_CPU0_RESET_N
J 0
(-8460 3235);
DISPLAY 0.489362 (-8460 3235);
WIRE 16 -1 (-7700 3175)(-8475 3175);
FORCEPROP 2 LAST SIG_NAME M_B_CPU0_ALERT_N
J 0
(-8460 3185);
DISPLAY 0.489362 (-8460 3185);
DOT 1 (-2250 5775);
DOT 1 (-2125 4725);
DOT 1 (-2825 5775);
DOT 1 (-2125 5175);
DOT 1 (-8550 2275);
DOT 1 (-2125 5225);
DOT 1 (-2125 2475);
DOT 1 (-2125 4575);
DOT 1 (-2125 3025);
DOT 1 (-2125 2425);
DOT 1 (-2125 1975);
DOT 1 (-2125 2025);
DOT 1 (-2125 2075);
DOT 1 (-2125 2175);
DOT 1 (-2125 2125);
DOT 1 (-2125 2225);
DOT 1 (-2125 2275);
DOT 1 (-2125 2325);
DOT 1 (-2125 2375);
DOT 1 (-2125 2775);
DOT 1 (-2125 2875);
DOT 1 (-2125 2925);
DOT 1 (-2125 2975);
DOT 1 (-2125 3075);
DOT 1 (-2125 3125);
DOT 1 (-2125 3175);
DOT 1 (-2125 3225);
DOT 1 (-2125 3375);
DOT 1 (-2125 3325);
DOT 1 (-2125 3275);
DOT 1 (-2125 3525);
DOT 1 (-2125 3575);
DOT 1 (-2125 3625);
DOT 1 (-2125 3725);
DOT 1 (-2125 3675);
DOT 1 (-2125 3775);
DOT 1 (-2125 3825);
DOT 1 (-2125 3875);
DOT 1 (-2125 3925);
DOT 1 (-2125 4025);
DOT 1 (-2125 4075);
DOT 1 (-2125 4125);
DOT 1 (-2125 4175);
DOT 1 (-325 1875);
DOT 1 (-325 1925);
DOT 1 (-325 1975);
DOT 1 (-325 2075);
DOT 1 (-325 2125);
DOT 1 (-325 2175);
DOT 1 (-325 2225);
DOT 1 (-325 2275);
DOT 1 (-325 2325);
DOT 1 (-325 2375);
DOT 1 (-325 2425);
DOT 1 (-325 2475);
DOT 1 (-325 2575);
DOT 1 (-325 2525);
DOT 1 (-325 2625);
DOT 1 (-325 2675);
DOT 1 (-325 2725);
DOT 1 (-325 2825);
DOT 1 (-325 2775);
DOT 1 (-325 2875);
DOT 1 (-325 2925);
DOT 1 (-325 2975);
DOT 1 (-325 3075);
DOT 1 (-325 3025);
DOT 1 (-325 3125);
DOT 1 (-325 3175);
DOT 1 (-325 3225);
DOT 1 (-325 3325);
DOT 1 (-325 3375);
DOT 1 (-325 3275);
DOT 1 (-325 3475);
DOT 1 (-325 3425);
DOT 1 (-325 3525);
DOT 1 (-325 3575);
DOT 1 (-325 3625);
DOT 1 (-325 3725);
DOT 1 (-325 3675);
DOT 1 (-325 3775);
DOT 1 (-325 3825);
DOT 1 (-325 3875);
DOT 1 (-325 3975);
DOT 1 (-325 3925);
DOT 1 (-325 4025);
DOT 1 (-325 4075);
DOT 1 (-325 4125);
DOT 1 (-325 4225);
DOT 1 (-325 4175);
DOT 1 (-325 4275);
DOT 1 (-2125 4525);
DOT 1 (-2125 4775);
DOT 1 (-325 4325);
DOT 1 (-325 4375);
DOT 1 (-325 4425);
DOT 1 (-325 4475);
DOT 1 (-325 4525);
DOT 1 (-325 4625);
DOT 1 (-325 4575);
DOT 1 (-325 4675);
DOT 1 (-325 4725);
DOT 1 (-325 4775);
DOT 1 (-325 4875);
DOT 1 (-325 4825);
DOT 1 (-325 4975);
DOT 1 (-325 4925);
DOT 1 (-325 5025);
DOT 1 (-325 5125);
DOT 1 (-325 5075);
DOT 1 (-325 5175);
DOT 1 (-2125 3425);
DOT 1 (-2125 3475);
DOT 1 (-2125 4225);
DOT 1 (-2125 4275);
DOT 1 (-2125 4325);
DOT 1 (-2125 4375);
DOT 1 (-2125 4425);
DOT 1 (-2125 4475);
DOT 1 (-2125 4625);
DOT 1 (-2125 4675);
DOT 1 (-2125 4825);
DOT 1 (-2125 4875);
DOT 1 (-2125 4925);
DOT 1 (-2125 4975);
DOT 1 (-2125 5025);
DOT 1 (-2125 2525);
DOT 1 (-2125 2575);
DOT 1 (-2125 2625);
DOT 1 (-2125 2675);
DOT 1 (-2125 2725);
DOT 1 (-2125 2825);
DOT 1 (-2125 3975);
DOT 1 (-2825 5350);
DOT 1 (-8925 3500);
QUIT
